FILE_TYPE = MACRO_DRAWING;
SET COLOR_WIRE YELLOW;
SET COLOR_PROP MONO;
SET COLOR_DOT WHITE;
SET COLOR_ARC YELLOW;
SET COLOR_BODY GREEN;
SET COLOR_NOTE MONO;
SET PROP_DISPLAY VALUE;
SET PAGE_NUMBER P59;
FORCEADD OFFPAGE..5
(-6425 500);
FORCEPROP 2 LAST $XR0 81 
J 0
(-6679 500);
DISPLAY 0.638298 (-6679 500);
PAINT MONO (-6679 500);
FORCEPROP 2 LAST $XR1 82 
J 0
(-6769 500);
DISPLAY 0.638298 (-6769 500);
PAINT MONO (-6769 500);
FORCEPROP 2 LAST CDS_LIB mstr_standard
J 0
(-6425 500);
PAINT MONO (-6425 500);
DISPLAY INVISIBLE (-6425 500);
FORCEPROP 1 LAST OFFPAGE TRUE
J 0
(-6100 375);
DISPLAY 1.170213 (-6100 375);
PAINT GREEN (-6100 375);
DISPLAY INVISIBLE (-6100 375);
FORCEPROP 1 LAST COMMENT_BODY TRUE
J 0
(-6325 425);
DISPLAY 1.170213 (-6325 425);
PAINT GREEN (-6325 425);
DISPLAY INVISIBLE (-6325 425);
FORCEPROP 2 LAST PATH I1
J 0
(-6375 575);
DISPLAY 1.021277 (-6375 575);
PAINT ORANGE (-6375 575);
DISPLAY INVISIBLE (-6375 575);
FORCEADD TAP..6
(-5575 800);
FORCEPROP 3 LASTPIN (-5525 800) SIG_NAME M_J_CLK_DP<0>
J 0
(-5515 810);
DISPLAY 0.659574 (-5515 810);
PAINT MONO (-5515 810);
DISPLAY INVISIBLE (-5515 810);
FORCEPROP 1 LASTPIN (-5525 800) BN 0
J 0
(-5577 808);
DISPLAY 0.617021 (-5577 808);
PAINT GREEN (-5577 808);
FORCEPROP 2 LAST CDS_LIB mstr_standard
J 0
(-5575 800);
PAINT MONO (-5575 800);
DISPLAY INVISIBLE (-5575 800);
FORCEPROP 1 LAST BODY_TYPE PLUMBING
J 0
(-5575 750);
DISPLAY 1.595745 (-5575 750);
PAINT GREEN (-5575 750);
DISPLAY INVISIBLE (-5575 750);
FORCEPROP 1 LAST HDL_TAP TRUE
J 0
(-5250 675);
DISPLAY 1.595745 (-5250 675);
PAINT GREEN (-5250 675);
DISPLAY INVISIBLE (-5250 675);
FORCEPROP 1 LAST PATH I10
J 0
(-5577 800);
DISPLAY 0.872340 (-5577 800);
PAINT GREEN (-5577 800);
DISPLAY INVISIBLE (-5577 800);
FORCEADD TAP..6
R 2
(-2850 1550);
FORCEPROP 3 LASTPIN (-2900 1550) SIG_NAME M_J_ODT<3>
J 0
(-2890 1560);
DISPLAY 0.659574 (-2890 1560);
PAINT MONO (-2890 1560);
DISPLAY INVISIBLE (-2890 1560);
FORCEPROP 1 LASTPIN (-2900 1550) BN 3
J 2
(-2848 1558);
DISPLAY 0.617021 (-2848 1558);
PAINT GREEN (-2848 1558);
FORCEPROP 2 LAST CDS_LIB mstr_standard
J 0
(-2850 1550);
PAINT MONO (-2850 1550);
DISPLAY INVISIBLE (-2850 1550);
FORCEPROP 1 LAST BODY_TYPE PLUMBING
J 2
(-2850 1500);
DISPLAY 1.595745 (-2850 1500);
PAINT GREEN (-2850 1500);
DISPLAY INVISIBLE (-2850 1500);
FORCEPROP 1 LAST HDL_TAP TRUE
J 2
(-3175 1425);
DISPLAY 1.595745 (-3175 1425);
PAINT GREEN (-3175 1425);
DISPLAY INVISIBLE (-3175 1425);
FORCEPROP 1 LAST PATH I100
J 2
(-2848 1550);
DISPLAY 0.872340 (-2848 1550);
PAINT GREEN (-2848 1550);
DISPLAY INVISIBLE (-2848 1550);
FORCEADD TAP..6
R 2
(-2850 1500);
FORCEPROP 3 LASTPIN (-2900 1500) SIG_NAME M_J_ODT<2>
J 0
(-2890 1510);
DISPLAY 0.659574 (-2890 1510);
PAINT MONO (-2890 1510);
DISPLAY INVISIBLE (-2890 1510);
FORCEPROP 1 LASTPIN (-2900 1500) BN 2
J 2
(-2848 1508);
DISPLAY 0.617021 (-2848 1508);
PAINT GREEN (-2848 1508);
FORCEPROP 2 LAST CDS_LIB mstr_standard
J 0
(-2850 1500);
PAINT MONO (-2850 1500);
DISPLAY INVISIBLE (-2850 1500);
FORCEPROP 1 LAST BODY_TYPE PLUMBING
J 2
(-2850 1450);
DISPLAY 1.595745 (-2850 1450);
PAINT GREEN (-2850 1450);
DISPLAY INVISIBLE (-2850 1450);
FORCEPROP 1 LAST HDL_TAP TRUE
J 2
(-3175 1375);
DISPLAY 1.595745 (-3175 1375);
PAINT GREEN (-3175 1375);
DISPLAY INVISIBLE (-3175 1375);
FORCEPROP 1 LAST PATH I101
J 2
(-2848 1500);
DISPLAY 0.872340 (-2848 1500);
PAINT GREEN (-2848 1500);
DISPLAY INVISIBLE (-2848 1500);
FORCEADD TAP..6
R 2
(-2850 1450);
FORCEPROP 3 LASTPIN (-2900 1450) SIG_NAME M_J_ODT<1>
J 0
(-2890 1460);
DISPLAY 0.659574 (-2890 1460);
PAINT MONO (-2890 1460);
DISPLAY INVISIBLE (-2890 1460);
FORCEPROP 1 LASTPIN (-2900 1450) BN 1
J 2
(-2848 1458);
DISPLAY 0.617021 (-2848 1458);
PAINT GREEN (-2848 1458);
FORCEPROP 2 LAST CDS_LIB mstr_standard
J 0
(-2850 1450);
PAINT MONO (-2850 1450);
DISPLAY INVISIBLE (-2850 1450);
FORCEPROP 1 LAST BODY_TYPE PLUMBING
J 2
(-2850 1400);
DISPLAY 1.595745 (-2850 1400);
PAINT GREEN (-2850 1400);
DISPLAY INVISIBLE (-2850 1400);
FORCEPROP 1 LAST HDL_TAP TRUE
J 2
(-3175 1325);
DISPLAY 1.595745 (-3175 1325);
PAINT GREEN (-3175 1325);
DISPLAY INVISIBLE (-3175 1325);
FORCEPROP 1 LAST PATH I102
J 2
(-2848 1450);
DISPLAY 0.872340 (-2848 1450);
PAINT GREEN (-2848 1450);
DISPLAY INVISIBLE (-2848 1450);
FORCEADD TAP..6
R 2
(-2850 1650);
FORCEPROP 3 LASTPIN (-2900 1650) SIG_NAME M_J_CKE <0>
J 0
(-2890 1660);
DISPLAY 0.659574 (-2890 1660);
PAINT MONO (-2890 1660);
DISPLAY INVISIBLE (-2890 1660);
FORCEPROP 1 LASTPIN (-2900 1650) BN 0
J 2
(-2848 1658);
DISPLAY 0.617021 (-2848 1658);
PAINT GREEN (-2848 1658);
FORCEPROP 2 LAST CDS_LIB mstr_standard
J 0
(-2850 1650);
PAINT MONO (-2850 1650);
DISPLAY INVISIBLE (-2850 1650);
FORCEPROP 1 LAST BODY_TYPE PLUMBING
J 2
(-2850 1600);
DISPLAY 1.595745 (-2850 1600);
PAINT GREEN (-2850 1600);
DISPLAY INVISIBLE (-2850 1600);
FORCEPROP 1 LAST HDL_TAP TRUE
J 2
(-3175 1525);
DISPLAY 1.595745 (-3175 1525);
PAINT GREEN (-3175 1525);
DISPLAY INVISIBLE (-3175 1525);
FORCEPROP 1 LAST PATH I103
J 2
(-2848 1650);
DISPLAY 0.872340 (-2848 1650);
PAINT GREEN (-2848 1650);
DISPLAY INVISIBLE (-2848 1650);
FORCEADD TAP..6
R 2
(-2850 1700);
FORCEPROP 3 LASTPIN (-2900 1700) SIG_NAME M_J_CKE <1>
J 0
(-2890 1710);
DISPLAY 0.659574 (-2890 1710);
PAINT MONO (-2890 1710);
DISPLAY INVISIBLE (-2890 1710);
FORCEPROP 1 LASTPIN (-2900 1700) BN 1
J 2
(-2848 1708);
DISPLAY 0.617021 (-2848 1708);
PAINT GREEN (-2848 1708);
FORCEPROP 2 LAST CDS_LIB mstr_standard
J 0
(-2850 1700);
PAINT MONO (-2850 1700);
DISPLAY INVISIBLE (-2850 1700);
FORCEPROP 1 LAST BODY_TYPE PLUMBING
J 2
(-2850 1650);
DISPLAY 1.595745 (-2850 1650);
PAINT GREEN (-2850 1650);
DISPLAY INVISIBLE (-2850 1650);
FORCEPROP 1 LAST HDL_TAP TRUE
J 2
(-3175 1575);
DISPLAY 1.595745 (-3175 1575);
PAINT GREEN (-3175 1575);
DISPLAY INVISIBLE (-3175 1575);
FORCEPROP 1 LAST PATH I104
J 2
(-2848 1700);
DISPLAY 0.872340 (-2848 1700);
PAINT GREEN (-2848 1700);
DISPLAY INVISIBLE (-2848 1700);
FORCEADD TAP..6
R 2
(-2850 1750);
FORCEPROP 3 LASTPIN (-2900 1750) SIG_NAME M_J_CKE <2>
J 0
(-2890 1760);
DISPLAY 0.659574 (-2890 1760);
PAINT MONO (-2890 1760);
DISPLAY INVISIBLE (-2890 1760);
FORCEPROP 1 LASTPIN (-2900 1750) BN 2
J 2
(-2848 1758);
DISPLAY 0.617021 (-2848 1758);
PAINT GREEN (-2848 1758);
FORCEPROP 2 LAST CDS_LIB mstr_standard
J 0
(-2850 1750);
PAINT MONO (-2850 1750);
DISPLAY INVISIBLE (-2850 1750);
FORCEPROP 1 LAST BODY_TYPE PLUMBING
J 2
(-2850 1700);
DISPLAY 1.595745 (-2850 1700);
PAINT GREEN (-2850 1700);
DISPLAY INVISIBLE (-2850 1700);
FORCEPROP 1 LAST HDL_TAP TRUE
J 2
(-3175 1625);
DISPLAY 1.595745 (-3175 1625);
PAINT GREEN (-3175 1625);
DISPLAY INVISIBLE (-3175 1625);
FORCEPROP 1 LAST PATH I105
J 2
(-2848 1750);
DISPLAY 0.872340 (-2848 1750);
PAINT GREEN (-2848 1750);
DISPLAY INVISIBLE (-2848 1750);
FORCEADD TAP..6
R 2
(-2850 1800);
FORCEPROP 3 LASTPIN (-2900 1800) SIG_NAME M_J_CKE <3>
J 0
(-2890 1810);
DISPLAY 0.659574 (-2890 1810);
PAINT MONO (-2890 1810);
DISPLAY INVISIBLE (-2890 1810);
FORCEPROP 1 LASTPIN (-2900 1800) BN 3
J 2
(-2848 1808);
DISPLAY 0.617021 (-2848 1808);
PAINT GREEN (-2848 1808);
FORCEPROP 2 LAST CDS_LIB mstr_standard
J 0
(-2850 1800);
PAINT MONO (-2850 1800);
DISPLAY INVISIBLE (-2850 1800);
FORCEPROP 1 LAST BODY_TYPE PLUMBING
J 2
(-2850 1750);
DISPLAY 1.595745 (-2850 1750);
PAINT GREEN (-2850 1750);
DISPLAY INVISIBLE (-2850 1750);
FORCEPROP 1 LAST HDL_TAP TRUE
J 2
(-3175 1675);
DISPLAY 1.595745 (-3175 1675);
PAINT GREEN (-3175 1675);
DISPLAY INVISIBLE (-3175 1675);
FORCEPROP 1 LAST PATH I106
J 2
(-2848 1800);
DISPLAY 0.872340 (-2848 1800);
PAINT GREEN (-2848 1800);
DISPLAY INVISIBLE (-2848 1800);
FORCEADD TAP..6
R 2
(-2850 1900);
FORCEPROP 3 LASTPIN (-2900 1900) SIG_NAME M_J_MA<0>
J 0
(-2890 1910);
DISPLAY 0.659574 (-2890 1910);
PAINT MONO (-2890 1910);
DISPLAY INVISIBLE (-2890 1910);
FORCEPROP 1 LASTPIN (-2900 1900) BN 0
J 2
(-2848 1908);
DISPLAY 0.617021 (-2848 1908);
PAINT GREEN (-2848 1908);
FORCEPROP 2 LAST CDS_LIB mstr_standard
J 0
(-2850 1900);
PAINT MONO (-2850 1900);
DISPLAY INVISIBLE (-2850 1900);
FORCEPROP 1 LAST BODY_TYPE PLUMBING
J 2
(-2850 1850);
DISPLAY 1.595745 (-2850 1850);
PAINT GREEN (-2850 1850);
DISPLAY INVISIBLE (-2850 1850);
FORCEPROP 1 LAST HDL_TAP TRUE
J 2
(-3175 1775);
DISPLAY 1.595745 (-3175 1775);
PAINT GREEN (-3175 1775);
DISPLAY INVISIBLE (-3175 1775);
FORCEPROP 1 LAST PATH I107
J 2
(-2848 1900);
DISPLAY 0.872340 (-2848 1900);
PAINT GREEN (-2848 1900);
DISPLAY INVISIBLE (-2848 1900);
FORCEADD TAP..6
R 2
(-2850 1950);
FORCEPROP 3 LASTPIN (-2900 1950) SIG_NAME M_J_MA<1>
J 0
(-2890 1960);
DISPLAY 0.659574 (-2890 1960);
PAINT MONO (-2890 1960);
DISPLAY INVISIBLE (-2890 1960);
FORCEPROP 1 LASTPIN (-2900 1950) BN 1
J 2
(-2848 1958);
DISPLAY 0.617021 (-2848 1958);
PAINT GREEN (-2848 1958);
FORCEPROP 2 LAST CDS_LIB mstr_standard
J 0
(-2850 1950);
PAINT MONO (-2850 1950);
DISPLAY INVISIBLE (-2850 1950);
FORCEPROP 1 LAST BODY_TYPE PLUMBING
J 2
(-2850 1900);
DISPLAY 1.595745 (-2850 1900);
PAINT GREEN (-2850 1900);
DISPLAY INVISIBLE (-2850 1900);
FORCEPROP 1 LAST HDL_TAP TRUE
J 2
(-3175 1825);
DISPLAY 1.595745 (-3175 1825);
PAINT GREEN (-3175 1825);
DISPLAY INVISIBLE (-3175 1825);
FORCEPROP 1 LAST PATH I108
J 2
(-2848 1950);
DISPLAY 0.872340 (-2848 1950);
PAINT GREEN (-2848 1950);
DISPLAY INVISIBLE (-2848 1950);
FORCEADD TAP..6
R 2
(-2850 2050);
FORCEPROP 3 LASTPIN (-2900 2050) SIG_NAME M_J_MA<3>
J 0
(-2890 2060);
DISPLAY 0.659574 (-2890 2060);
PAINT MONO (-2890 2060);
DISPLAY INVISIBLE (-2890 2060);
FORCEPROP 1 LASTPIN (-2900 2050) BN 3
J 2
(-2848 2058);
DISPLAY 0.617021 (-2848 2058);
PAINT GREEN (-2848 2058);
FORCEPROP 2 LAST CDS_LIB mstr_standard
J 0
(-2850 2050);
PAINT MONO (-2850 2050);
DISPLAY INVISIBLE (-2850 2050);
FORCEPROP 1 LAST BODY_TYPE PLUMBING
J 2
(-2850 2000);
DISPLAY 1.595745 (-2850 2000);
PAINT GREEN (-2850 2000);
DISPLAY INVISIBLE (-2850 2000);
FORCEPROP 1 LAST HDL_TAP TRUE
J 2
(-3175 1925);
DISPLAY 1.595745 (-3175 1925);
PAINT GREEN (-3175 1925);
DISPLAY INVISIBLE (-3175 1925);
FORCEPROP 1 LAST PATH I109
J 2
(-2848 2050);
DISPLAY 0.872340 (-2848 2050);
PAINT GREEN (-2848 2050);
DISPLAY INVISIBLE (-2848 2050);
FORCEADD TAP..6
(-5575 900);
FORCEPROP 3 LASTPIN (-5525 900) SIG_NAME M_J_CLK_DP<2>
J 0
(-5515 910);
DISPLAY 0.659574 (-5515 910);
PAINT MONO (-5515 910);
DISPLAY INVISIBLE (-5515 910);
FORCEPROP 1 LASTPIN (-5525 900) BN 2
J 0
(-5577 908);
DISPLAY 0.617021 (-5577 908);
PAINT GREEN (-5577 908);
FORCEPROP 2 LAST CDS_LIB mstr_standard
J 0
(-5575 900);
PAINT MONO (-5575 900);
DISPLAY INVISIBLE (-5575 900);
FORCEPROP 1 LAST BODY_TYPE PLUMBING
J 0
(-5575 850);
DISPLAY 1.595745 (-5575 850);
PAINT GREEN (-5575 850);
DISPLAY INVISIBLE (-5575 850);
FORCEPROP 1 LAST HDL_TAP TRUE
J 0
(-5250 775);
DISPLAY 1.595745 (-5250 775);
PAINT GREEN (-5250 775);
DISPLAY INVISIBLE (-5250 775);
FORCEPROP 1 LAST PATH I11
J 0
(-5577 900);
DISPLAY 0.872340 (-5577 900);
PAINT GREEN (-5577 900);
DISPLAY INVISIBLE (-5577 900);
FORCEADD TAP..6
R 2
(-2850 2000);
FORCEPROP 3 LASTPIN (-2900 2000) SIG_NAME M_J_MA<2>
J 0
(-2890 2010);
DISPLAY 0.659574 (-2890 2010);
PAINT MONO (-2890 2010);
DISPLAY INVISIBLE (-2890 2010);
FORCEPROP 1 LASTPIN (-2900 2000) BN 2
J 2
(-2848 2008);
DISPLAY 0.617021 (-2848 2008);
PAINT GREEN (-2848 2008);
FORCEPROP 2 LAST CDS_LIB mstr_standard
J 0
(-2850 2000);
PAINT MONO (-2850 2000);
DISPLAY INVISIBLE (-2850 2000);
FORCEPROP 1 LAST BODY_TYPE PLUMBING
J 2
(-2850 1950);
DISPLAY 1.595745 (-2850 1950);
PAINT GREEN (-2850 1950);
DISPLAY INVISIBLE (-2850 1950);
FORCEPROP 1 LAST HDL_TAP TRUE
J 2
(-3175 1875);
DISPLAY 1.595745 (-3175 1875);
PAINT GREEN (-3175 1875);
DISPLAY INVISIBLE (-3175 1875);
FORCEPROP 1 LAST PATH I110
J 2
(-2848 2000);
DISPLAY 0.872340 (-2848 2000);
PAINT GREEN (-2848 2000);
DISPLAY INVISIBLE (-2848 2000);
FORCEADD TAP..6
R 2
(-2850 2100);
FORCEPROP 3 LASTPIN (-2900 2100) SIG_NAME M_J_MA<4>
J 0
(-2890 2110);
DISPLAY 0.659574 (-2890 2110);
PAINT MONO (-2890 2110);
DISPLAY INVISIBLE (-2890 2110);
FORCEPROP 1 LASTPIN (-2900 2100) BN 4
J 2
(-2848 2108);
DISPLAY 0.617021 (-2848 2108);
PAINT GREEN (-2848 2108);
FORCEPROP 2 LAST CDS_LIB mstr_standard
J 0
(-2850 2100);
PAINT MONO (-2850 2100);
DISPLAY INVISIBLE (-2850 2100);
FORCEPROP 1 LAST BODY_TYPE PLUMBING
J 2
(-2850 2050);
DISPLAY 1.595745 (-2850 2050);
PAINT GREEN (-2850 2050);
DISPLAY INVISIBLE (-2850 2050);
FORCEPROP 1 LAST HDL_TAP TRUE
J 2
(-3175 1975);
DISPLAY 1.595745 (-3175 1975);
PAINT GREEN (-3175 1975);
DISPLAY INVISIBLE (-3175 1975);
FORCEPROP 1 LAST PATH I111
J 2
(-2848 2100);
DISPLAY 0.872340 (-2848 2100);
PAINT GREEN (-2848 2100);
DISPLAY INVISIBLE (-2848 2100);
FORCEADD TAP..6
R 2
(-2850 2150);
FORCEPROP 3 LASTPIN (-2900 2150) SIG_NAME M_J_MA<5>
J 0
(-2890 2160);
DISPLAY 0.659574 (-2890 2160);
PAINT MONO (-2890 2160);
DISPLAY INVISIBLE (-2890 2160);
FORCEPROP 1 LASTPIN (-2900 2150) BN 5
J 2
(-2848 2158);
DISPLAY 0.617021 (-2848 2158);
PAINT GREEN (-2848 2158);
FORCEPROP 2 LAST CDS_LIB mstr_standard
J 0
(-2850 2150);
PAINT MONO (-2850 2150);
DISPLAY INVISIBLE (-2850 2150);
FORCEPROP 1 LAST BODY_TYPE PLUMBING
J 2
(-2850 2100);
DISPLAY 1.595745 (-2850 2100);
PAINT GREEN (-2850 2100);
DISPLAY INVISIBLE (-2850 2100);
FORCEPROP 1 LAST HDL_TAP TRUE
J 2
(-3175 2025);
DISPLAY 1.595745 (-3175 2025);
PAINT GREEN (-3175 2025);
DISPLAY INVISIBLE (-3175 2025);
FORCEPROP 1 LAST PATH I112
J 2
(-2848 2150);
DISPLAY 0.872340 (-2848 2150);
PAINT GREEN (-2848 2150);
DISPLAY INVISIBLE (-2848 2150);
FORCEADD TAP..6
R 2
(-2850 2200);
FORCEPROP 3 LASTPIN (-2900 2200) SIG_NAME M_J_MA<6>
J 0
(-2890 2210);
DISPLAY 0.659574 (-2890 2210);
PAINT MONO (-2890 2210);
DISPLAY INVISIBLE (-2890 2210);
FORCEPROP 1 LASTPIN (-2900 2200) BN 6
J 2
(-2848 2208);
DISPLAY 0.617021 (-2848 2208);
PAINT GREEN (-2848 2208);
FORCEPROP 2 LAST CDS_LIB mstr_standard
J 0
(-2850 2200);
PAINT MONO (-2850 2200);
DISPLAY INVISIBLE (-2850 2200);
FORCEPROP 1 LAST BODY_TYPE PLUMBING
J 2
(-2850 2150);
DISPLAY 1.595745 (-2850 2150);
PAINT GREEN (-2850 2150);
DISPLAY INVISIBLE (-2850 2150);
FORCEPROP 1 LAST HDL_TAP TRUE
J 2
(-3175 2075);
DISPLAY 1.595745 (-3175 2075);
PAINT GREEN (-3175 2075);
DISPLAY INVISIBLE (-3175 2075);
FORCEPROP 1 LAST PATH I113
J 2
(-2848 2200);
DISPLAY 0.872340 (-2848 2200);
PAINT GREEN (-2848 2200);
DISPLAY INVISIBLE (-2848 2200);
FORCEADD TAP..6
R 2
(-2850 2300);
FORCEPROP 3 LASTPIN (-2900 2300) SIG_NAME M_J_MA<8>
J 0
(-2890 2310);
DISPLAY 0.659574 (-2890 2310);
PAINT MONO (-2890 2310);
DISPLAY INVISIBLE (-2890 2310);
FORCEPROP 1 LASTPIN (-2900 2300) BN 8
J 2
(-2848 2308);
DISPLAY 0.617021 (-2848 2308);
PAINT GREEN (-2848 2308);
FORCEPROP 2 LAST CDS_LIB mstr_standard
J 0
(-2850 2300);
PAINT MONO (-2850 2300);
DISPLAY INVISIBLE (-2850 2300);
FORCEPROP 1 LAST BODY_TYPE PLUMBING
J 2
(-2850 2250);
DISPLAY 1.595745 (-2850 2250);
PAINT GREEN (-2850 2250);
DISPLAY INVISIBLE (-2850 2250);
FORCEPROP 1 LAST HDL_TAP TRUE
J 2
(-3175 2175);
DISPLAY 1.595745 (-3175 2175);
PAINT GREEN (-3175 2175);
DISPLAY INVISIBLE (-3175 2175);
FORCEPROP 1 LAST PATH I114
J 2
(-2848 2300);
DISPLAY 0.872340 (-2848 2300);
PAINT GREEN (-2848 2300);
DISPLAY INVISIBLE (-2848 2300);
FORCEADD TAP..6
R 2
(-2850 2250);
FORCEPROP 3 LASTPIN (-2900 2250) SIG_NAME M_J_MA<7>
J 0
(-2890 2260);
DISPLAY 0.659574 (-2890 2260);
PAINT MONO (-2890 2260);
DISPLAY INVISIBLE (-2890 2260);
FORCEPROP 1 LASTPIN (-2900 2250) BN 7
J 2
(-2848 2258);
DISPLAY 0.617021 (-2848 2258);
PAINT GREEN (-2848 2258);
FORCEPROP 2 LAST CDS_LIB mstr_standard
J 0
(-2850 2250);
PAINT MONO (-2850 2250);
DISPLAY INVISIBLE (-2850 2250);
FORCEPROP 1 LAST BODY_TYPE PLUMBING
J 2
(-2850 2200);
DISPLAY 1.595745 (-2850 2200);
PAINT GREEN (-2850 2200);
DISPLAY INVISIBLE (-2850 2200);
FORCEPROP 1 LAST HDL_TAP TRUE
J 2
(-3175 2125);
DISPLAY 1.595745 (-3175 2125);
PAINT GREEN (-3175 2125);
DISPLAY INVISIBLE (-3175 2125);
FORCEPROP 1 LAST PATH I115
J 2
(-2848 2250);
DISPLAY 0.872340 (-2848 2250);
PAINT GREEN (-2848 2250);
DISPLAY INVISIBLE (-2848 2250);
FORCEADD TAP..6
R 2
(-2850 2450);
FORCEPROP 3 LASTPIN (-2900 2450) SIG_NAME M_J_MA<11>
J 0
(-2890 2460);
DISPLAY 0.659574 (-2890 2460);
PAINT MONO (-2890 2460);
DISPLAY INVISIBLE (-2890 2460);
FORCEPROP 1 LASTPIN (-2900 2450) BN 11
J 2
(-2848 2458);
DISPLAY 0.617021 (-2848 2458);
PAINT GREEN (-2848 2458);
FORCEPROP 2 LAST CDS_LIB mstr_standard
J 0
(-2850 2450);
PAINT MONO (-2850 2450);
DISPLAY INVISIBLE (-2850 2450);
FORCEPROP 1 LAST BODY_TYPE PLUMBING
J 2
(-2850 2400);
DISPLAY 1.595745 (-2850 2400);
PAINT GREEN (-2850 2400);
DISPLAY INVISIBLE (-2850 2400);
FORCEPROP 1 LAST HDL_TAP TRUE
J 2
(-3175 2325);
DISPLAY 1.595745 (-3175 2325);
PAINT GREEN (-3175 2325);
DISPLAY INVISIBLE (-3175 2325);
FORCEPROP 1 LAST PATH I116
J 2
(-2848 2450);
DISPLAY 0.872340 (-2848 2450);
PAINT GREEN (-2848 2450);
DISPLAY INVISIBLE (-2848 2450);
FORCEADD TAP..6
R 2
(-2850 2400);
FORCEPROP 3 LASTPIN (-2900 2400) SIG_NAME M_J_MA<10>
J 0
(-2890 2410);
DISPLAY 0.659574 (-2890 2410);
PAINT MONO (-2890 2410);
DISPLAY INVISIBLE (-2890 2410);
FORCEPROP 1 LASTPIN (-2900 2400) BN 10
J 2
(-2848 2408);
DISPLAY 0.617021 (-2848 2408);
PAINT GREEN (-2848 2408);
FORCEPROP 2 LAST CDS_LIB mstr_standard
J 0
(-2850 2400);
PAINT MONO (-2850 2400);
DISPLAY INVISIBLE (-2850 2400);
FORCEPROP 1 LAST BODY_TYPE PLUMBING
J 2
(-2850 2350);
DISPLAY 1.595745 (-2850 2350);
PAINT GREEN (-2850 2350);
DISPLAY INVISIBLE (-2850 2350);
FORCEPROP 1 LAST HDL_TAP TRUE
J 2
(-3175 2275);
DISPLAY 1.595745 (-3175 2275);
PAINT GREEN (-3175 2275);
DISPLAY INVISIBLE (-3175 2275);
FORCEPROP 1 LAST PATH I117
J 2
(-2848 2400);
DISPLAY 0.872340 (-2848 2400);
PAINT GREEN (-2848 2400);
DISPLAY INVISIBLE (-2848 2400);
FORCEADD TAP..6
R 2
(-2850 2350);
FORCEPROP 3 LASTPIN (-2900 2350) SIG_NAME M_J_MA<9>
J 0
(-2890 2360);
DISPLAY 0.659574 (-2890 2360);
PAINT MONO (-2890 2360);
DISPLAY INVISIBLE (-2890 2360);
FORCEPROP 1 LASTPIN (-2900 2350) BN 9
J 2
(-2848 2358);
DISPLAY 0.617021 (-2848 2358);
PAINT GREEN (-2848 2358);
FORCEPROP 2 LAST CDS_LIB mstr_standard
J 0
(-2850 2350);
PAINT MONO (-2850 2350);
DISPLAY INVISIBLE (-2850 2350);
FORCEPROP 1 LAST BODY_TYPE PLUMBING
J 2
(-2850 2300);
DISPLAY 1.595745 (-2850 2300);
PAINT GREEN (-2850 2300);
DISPLAY INVISIBLE (-2850 2300);
FORCEPROP 1 LAST HDL_TAP TRUE
J 2
(-3175 2225);
DISPLAY 1.595745 (-3175 2225);
PAINT GREEN (-3175 2225);
DISPLAY INVISIBLE (-3175 2225);
FORCEPROP 1 LAST PATH I118
J 2
(-2848 2350);
DISPLAY 0.872340 (-2848 2350);
PAINT GREEN (-2848 2350);
DISPLAY INVISIBLE (-2848 2350);
FORCEADD TAP..6
R 2
(-2850 2500);
FORCEPROP 3 LASTPIN (-2900 2500) SIG_NAME M_J_MA<12>
J 0
(-2890 2510);
DISPLAY 0.659574 (-2890 2510);
PAINT MONO (-2890 2510);
DISPLAY INVISIBLE (-2890 2510);
FORCEPROP 1 LASTPIN (-2900 2500) BN 12
J 2
(-2848 2508);
DISPLAY 0.617021 (-2848 2508);
PAINT GREEN (-2848 2508);
FORCEPROP 2 LAST CDS_LIB mstr_standard
J 0
(-2850 2500);
PAINT MONO (-2850 2500);
DISPLAY INVISIBLE (-2850 2500);
FORCEPROP 1 LAST BODY_TYPE PLUMBING
J 2
(-2850 2450);
DISPLAY 1.595745 (-2850 2450);
PAINT GREEN (-2850 2450);
DISPLAY INVISIBLE (-2850 2450);
FORCEPROP 1 LAST HDL_TAP TRUE
J 2
(-3175 2375);
DISPLAY 1.595745 (-3175 2375);
PAINT GREEN (-3175 2375);
DISPLAY INVISIBLE (-3175 2375);
FORCEPROP 1 LAST PATH I119
J 2
(-2848 2500);
DISPLAY 0.872340 (-2848 2500);
PAINT GREEN (-2848 2500);
DISPLAY INVISIBLE (-2848 2500);
FORCEADD TAP..6
(-5575 950);
FORCEPROP 3 LASTPIN (-5525 950) SIG_NAME M_J_CLK_DP<3>
J 0
(-5515 960);
DISPLAY 0.659574 (-5515 960);
PAINT MONO (-5515 960);
DISPLAY INVISIBLE (-5515 960);
FORCEPROP 1 LASTPIN (-5525 950) BN 3
J 0
(-5577 958);
DISPLAY 0.617021 (-5577 958);
PAINT GREEN (-5577 958);
FORCEPROP 2 LAST CDS_LIB mstr_standard
J 0
(-5575 950);
PAINT MONO (-5575 950);
DISPLAY INVISIBLE (-5575 950);
FORCEPROP 1 LAST BODY_TYPE PLUMBING
J 0
(-5575 900);
DISPLAY 1.595745 (-5575 900);
PAINT GREEN (-5575 900);
DISPLAY INVISIBLE (-5575 900);
FORCEPROP 1 LAST HDL_TAP TRUE
J 0
(-5250 825);
DISPLAY 1.595745 (-5250 825);
PAINT GREEN (-5250 825);
DISPLAY INVISIBLE (-5250 825);
FORCEPROP 1 LAST PATH I12
J 0
(-5577 950);
DISPLAY 0.872340 (-5577 950);
PAINT GREEN (-5577 950);
DISPLAY INVISIBLE (-5577 950);
FORCEADD TAP..6
R 2
(-2850 2550);
FORCEPROP 3 LASTPIN (-2900 2550) SIG_NAME M_J_MA<13>
J 0
(-2890 2560);
DISPLAY 0.659574 (-2890 2560);
PAINT MONO (-2890 2560);
DISPLAY INVISIBLE (-2890 2560);
FORCEPROP 1 LASTPIN (-2900 2550) BN 13
J 2
(-2848 2558);
DISPLAY 0.617021 (-2848 2558);
PAINT GREEN (-2848 2558);
FORCEPROP 2 LAST CDS_LIB mstr_standard
J 0
(-2850 2550);
PAINT MONO (-2850 2550);
DISPLAY INVISIBLE (-2850 2550);
FORCEPROP 1 LAST BODY_TYPE PLUMBING
J 2
(-2850 2500);
DISPLAY 1.595745 (-2850 2500);
PAINT GREEN (-2850 2500);
DISPLAY INVISIBLE (-2850 2500);
FORCEPROP 1 LAST HDL_TAP TRUE
J 2
(-3175 2425);
DISPLAY 1.595745 (-3175 2425);
PAINT GREEN (-3175 2425);
DISPLAY INVISIBLE (-3175 2425);
FORCEPROP 1 LAST PATH I120
J 2
(-2848 2550);
DISPLAY 0.872340 (-2848 2550);
PAINT GREEN (-2848 2550);
DISPLAY INVISIBLE (-2848 2550);
FORCEADD TAP..6
R 2
(-2850 2600);
FORCEPROP 3 LASTPIN (-2900 2600) SIG_NAME M_J_MA<14>
J 0
(-2890 2610);
DISPLAY 0.659574 (-2890 2610);
PAINT MONO (-2890 2610);
DISPLAY INVISIBLE (-2890 2610);
FORCEPROP 1 LASTPIN (-2900 2600) BN 14
J 2
(-2848 2608);
DISPLAY 0.617021 (-2848 2608);
PAINT GREEN (-2848 2608);
FORCEPROP 2 LAST CDS_LIB mstr_standard
J 0
(-2850 2600);
PAINT MONO (-2850 2600);
DISPLAY INVISIBLE (-2850 2600);
FORCEPROP 1 LAST BODY_TYPE PLUMBING
J 2
(-2850 2550);
DISPLAY 1.595745 (-2850 2550);
PAINT GREEN (-2850 2550);
DISPLAY INVISIBLE (-2850 2550);
FORCEPROP 1 LAST HDL_TAP TRUE
J 2
(-3175 2475);
DISPLAY 1.595745 (-3175 2475);
PAINT GREEN (-3175 2475);
DISPLAY INVISIBLE (-3175 2475);
FORCEPROP 1 LAST PATH I121
J 2
(-2848 2600);
DISPLAY 0.872340 (-2848 2600);
PAINT GREEN (-2848 2600);
DISPLAY INVISIBLE (-2848 2600);
FORCEADD TAP..6
R 2
(-2850 2650);
FORCEPROP 3 LASTPIN (-2900 2650) SIG_NAME M_J_MA<15>
J 0
(-2890 2660);
DISPLAY 0.659574 (-2890 2660);
PAINT MONO (-2890 2660);
DISPLAY INVISIBLE (-2890 2660);
FORCEPROP 1 LASTPIN (-2900 2650) BN 15
J 2
(-2848 2658);
DISPLAY 0.617021 (-2848 2658);
PAINT GREEN (-2848 2658);
FORCEPROP 2 LAST CDS_LIB mstr_standard
J 0
(-2850 2650);
PAINT MONO (-2850 2650);
DISPLAY INVISIBLE (-2850 2650);
FORCEPROP 1 LAST BODY_TYPE PLUMBING
J 2
(-2850 2600);
DISPLAY 1.595745 (-2850 2600);
PAINT GREEN (-2850 2600);
DISPLAY INVISIBLE (-2850 2600);
FORCEPROP 1 LAST HDL_TAP TRUE
J 2
(-3175 2525);
DISPLAY 1.595745 (-3175 2525);
PAINT GREEN (-3175 2525);
DISPLAY INVISIBLE (-3175 2525);
FORCEPROP 1 LAST PATH I122
J 2
(-2848 2650);
DISPLAY 0.872340 (-2848 2650);
PAINT GREEN (-2848 2650);
DISPLAY INVISIBLE (-2848 2650);
FORCEADD TAP..6
R 2
(-2850 2700);
FORCEPROP 3 LASTPIN (-2900 2700) SIG_NAME M_J_MA<16>
J 0
(-2890 2710);
DISPLAY 0.659574 (-2890 2710);
PAINT MONO (-2890 2710);
DISPLAY INVISIBLE (-2890 2710);
FORCEPROP 1 LASTPIN (-2900 2700) BN 16
J 2
(-2848 2708);
DISPLAY 0.617021 (-2848 2708);
PAINT GREEN (-2848 2708);
FORCEPROP 2 LAST CDS_LIB mstr_standard
J 0
(-2850 2700);
PAINT MONO (-2850 2700);
DISPLAY INVISIBLE (-2850 2700);
FORCEPROP 1 LAST BODY_TYPE PLUMBING
J 2
(-2850 2650);
DISPLAY 1.595745 (-2850 2650);
PAINT GREEN (-2850 2650);
DISPLAY INVISIBLE (-2850 2650);
FORCEPROP 1 LAST HDL_TAP TRUE
J 2
(-3175 2575);
DISPLAY 1.595745 (-3175 2575);
PAINT GREEN (-3175 2575);
DISPLAY INVISIBLE (-3175 2575);
FORCEPROP 1 LAST PATH I123
J 2
(-2848 2700);
DISPLAY 0.872340 (-2848 2700);
PAINT GREEN (-2848 2700);
DISPLAY INVISIBLE (-2848 2700);
FORCEADD TAP..6
R 2
(-2850 2750);
FORCEPROP 3 LASTPIN (-2900 2750) SIG_NAME M_J_MA<17>
J 0
(-2890 2760);
DISPLAY 0.659574 (-2890 2760);
PAINT MONO (-2890 2760);
DISPLAY INVISIBLE (-2890 2760);
FORCEPROP 1 LASTPIN (-2900 2750) BN 17
J 2
(-2848 2758);
DISPLAY 0.617021 (-2848 2758);
PAINT GREEN (-2848 2758);
FORCEPROP 2 LAST CDS_LIB mstr_standard
J 0
(-2850 2750);
PAINT MONO (-2850 2750);
DISPLAY INVISIBLE (-2850 2750);
FORCEPROP 1 LAST BODY_TYPE PLUMBING
J 2
(-2850 2700);
DISPLAY 1.595745 (-2850 2700);
PAINT GREEN (-2850 2700);
DISPLAY INVISIBLE (-2850 2700);
FORCEPROP 1 LAST HDL_TAP TRUE
J 2
(-3175 2625);
DISPLAY 1.595745 (-3175 2625);
PAINT GREEN (-3175 2625);
DISPLAY INVISIBLE (-3175 2625);
FORCEPROP 1 LAST PATH I124
J 2
(-2848 2750);
DISPLAY 0.872340 (-2848 2750);
PAINT GREEN (-2848 2750);
DISPLAY INVISIBLE (-2848 2750);
FORCEADD TAP..6
R 2
(-2850 2900);
FORCEPROP 3 LASTPIN (-2900 2900) SIG_NAME M_J_DQS_DN<1>
J 0
(-2890 2910);
DISPLAY 0.659574 (-2890 2910);
PAINT MONO (-2890 2910);
DISPLAY INVISIBLE (-2890 2910);
FORCEPROP 1 LASTPIN (-2900 2900) BN 1
J 2
(-2848 2908);
DISPLAY 0.617021 (-2848 2908);
PAINT GREEN (-2848 2908);
FORCEPROP 2 LAST CDS_LIB mstr_standard
J 0
(-2850 2900);
PAINT MONO (-2850 2900);
DISPLAY INVISIBLE (-2850 2900);
FORCEPROP 1 LAST BODY_TYPE PLUMBING
J 2
(-2850 2850);
DISPLAY 1.595745 (-2850 2850);
PAINT GREEN (-2850 2850);
DISPLAY INVISIBLE (-2850 2850);
FORCEPROP 1 LAST HDL_TAP TRUE
J 2
(-3175 2775);
DISPLAY 1.595745 (-3175 2775);
PAINT GREEN (-3175 2775);
DISPLAY INVISIBLE (-3175 2775);
FORCEPROP 1 LAST PATH I125
J 2
(-2848 2900);
DISPLAY 0.872340 (-2848 2900);
PAINT GREEN (-2848 2900);
DISPLAY INVISIBLE (-2848 2900);
FORCEADD TAP..6
R 2
(-2850 2950);
FORCEPROP 3 LASTPIN (-2900 2950) SIG_NAME M_J_DQS_DN<2>
J 0
(-2890 2960);
DISPLAY 0.659574 (-2890 2960);
PAINT MONO (-2890 2960);
DISPLAY INVISIBLE (-2890 2960);
FORCEPROP 1 LASTPIN (-2900 2950) BN 2
J 2
(-2848 2958);
DISPLAY 0.617021 (-2848 2958);
PAINT GREEN (-2848 2958);
FORCEPROP 2 LAST CDS_LIB mstr_standard
J 0
(-2850 2950);
PAINT MONO (-2850 2950);
DISPLAY INVISIBLE (-2850 2950);
FORCEPROP 1 LAST BODY_TYPE PLUMBING
J 2
(-2850 2900);
DISPLAY 1.595745 (-2850 2900);
PAINT GREEN (-2850 2900);
DISPLAY INVISIBLE (-2850 2900);
FORCEPROP 1 LAST HDL_TAP TRUE
J 2
(-3175 2825);
DISPLAY 1.595745 (-3175 2825);
PAINT GREEN (-3175 2825);
DISPLAY INVISIBLE (-3175 2825);
FORCEPROP 1 LAST PATH I126
J 2
(-2848 2950);
DISPLAY 0.872340 (-2848 2950);
PAINT GREEN (-2848 2950);
DISPLAY INVISIBLE (-2848 2950);
FORCEADD TAP..6
R 2
(-2850 2850);
FORCEPROP 3 LASTPIN (-2900 2850) SIG_NAME M_J_DQS_DN<0>
J 0
(-2890 2860);
DISPLAY 0.659574 (-2890 2860);
PAINT MONO (-2890 2860);
DISPLAY INVISIBLE (-2890 2860);
FORCEPROP 1 LASTPIN (-2900 2850) BN 0
J 2
(-2848 2858);
DISPLAY 0.617021 (-2848 2858);
PAINT GREEN (-2848 2858);
FORCEPROP 2 LAST CDS_LIB mstr_standard
J 0
(-2850 2850);
PAINT MONO (-2850 2850);
DISPLAY INVISIBLE (-2850 2850);
FORCEPROP 1 LAST BODY_TYPE PLUMBING
J 2
(-2850 2800);
DISPLAY 1.595745 (-2850 2800);
PAINT GREEN (-2850 2800);
DISPLAY INVISIBLE (-2850 2800);
FORCEPROP 1 LAST HDL_TAP TRUE
J 2
(-3175 2725);
DISPLAY 1.595745 (-3175 2725);
PAINT GREEN (-3175 2725);
DISPLAY INVISIBLE (-3175 2725);
FORCEPROP 1 LAST PATH I127
J 2
(-2848 2850);
DISPLAY 0.872340 (-2848 2850);
PAINT GREEN (-2848 2850);
DISPLAY INVISIBLE (-2848 2850);
FORCEADD TAP..6
R 2
(-2850 3050);
FORCEPROP 3 LASTPIN (-2900 3050) SIG_NAME M_J_DQS_DN<4>
J 0
(-2890 3060);
DISPLAY 0.659574 (-2890 3060);
PAINT MONO (-2890 3060);
DISPLAY INVISIBLE (-2890 3060);
FORCEPROP 1 LASTPIN (-2900 3050) BN 4
J 2
(-2848 3058);
DISPLAY 0.617021 (-2848 3058);
PAINT GREEN (-2848 3058);
FORCEPROP 2 LAST CDS_LIB mstr_standard
J 0
(-2850 3050);
PAINT MONO (-2850 3050);
DISPLAY INVISIBLE (-2850 3050);
FORCEPROP 1 LAST BODY_TYPE PLUMBING
J 2
(-2850 3000);
DISPLAY 1.595745 (-2850 3000);
PAINT GREEN (-2850 3000);
DISPLAY INVISIBLE (-2850 3000);
FORCEPROP 1 LAST HDL_TAP TRUE
J 2
(-3175 2925);
DISPLAY 1.595745 (-3175 2925);
PAINT GREEN (-3175 2925);
DISPLAY INVISIBLE (-3175 2925);
FORCEPROP 1 LAST PATH I128
J 2
(-2848 3050);
DISPLAY 0.872340 (-2848 3050);
PAINT GREEN (-2848 3050);
DISPLAY INVISIBLE (-2848 3050);
FORCEADD TAP..6
R 2
(-2850 3000);
FORCEPROP 3 LASTPIN (-2900 3000) SIG_NAME M_J_DQS_DN<3>
J 0
(-2890 3010);
DISPLAY 0.659574 (-2890 3010);
PAINT MONO (-2890 3010);
DISPLAY INVISIBLE (-2890 3010);
FORCEPROP 1 LASTPIN (-2900 3000) BN 3
J 2
(-2848 3008);
DISPLAY 0.617021 (-2848 3008);
PAINT GREEN (-2848 3008);
FORCEPROP 2 LAST CDS_LIB mstr_standard
J 0
(-2850 3000);
PAINT MONO (-2850 3000);
DISPLAY INVISIBLE (-2850 3000);
FORCEPROP 1 LAST BODY_TYPE PLUMBING
J 2
(-2850 2950);
DISPLAY 1.595745 (-2850 2950);
PAINT GREEN (-2850 2950);
DISPLAY INVISIBLE (-2850 2950);
FORCEPROP 1 LAST HDL_TAP TRUE
J 2
(-3175 2875);
DISPLAY 1.595745 (-3175 2875);
PAINT GREEN (-3175 2875);
DISPLAY INVISIBLE (-3175 2875);
FORCEPROP 1 LAST PATH I129
J 2
(-2848 3000);
DISPLAY 0.872340 (-2848 3000);
PAINT GREEN (-2848 3000);
DISPLAY INVISIBLE (-2848 3000);
FORCEADD TAP..6
(-5575 1050);
FORCEPROP 3 LASTPIN (-5525 1050) SIG_NAME M_J_ECC<0>
J 0
(-5515 1060);
DISPLAY 0.659574 (-5515 1060);
PAINT MONO (-5515 1060);
DISPLAY INVISIBLE (-5515 1060);
FORCEPROP 1 LASTPIN (-5525 1050) BN 0
J 0
(-5577 1058);
DISPLAY 0.617021 (-5577 1058);
PAINT GREEN (-5577 1058);
FORCEPROP 2 LAST CDS_LIB mstr_standard
J 0
(-5575 1050);
PAINT MONO (-5575 1050);
DISPLAY INVISIBLE (-5575 1050);
FORCEPROP 1 LAST BODY_TYPE PLUMBING
J 0
(-5575 1000);
DISPLAY 1.595745 (-5575 1000);
PAINT GREEN (-5575 1000);
DISPLAY INVISIBLE (-5575 1000);
FORCEPROP 1 LAST HDL_TAP TRUE
J 0
(-5250 925);
DISPLAY 1.595745 (-5250 925);
PAINT GREEN (-5250 925);
DISPLAY INVISIBLE (-5250 925);
FORCEPROP 1 LAST PATH I13
J 0
(-5577 1050);
DISPLAY 0.872340 (-5577 1050);
PAINT GREEN (-5577 1050);
DISPLAY INVISIBLE (-5577 1050);
FORCEADD TAP..6
R 2
(-2850 3100);
FORCEPROP 3 LASTPIN (-2900 3100) SIG_NAME M_J_DQS_DN<5>
J 0
(-2890 3110);
DISPLAY 0.659574 (-2890 3110);
PAINT MONO (-2890 3110);
DISPLAY INVISIBLE (-2890 3110);
FORCEPROP 1 LASTPIN (-2900 3100) BN 5
J 2
(-2848 3108);
DISPLAY 0.617021 (-2848 3108);
PAINT GREEN (-2848 3108);
FORCEPROP 2 LAST CDS_LIB mstr_standard
J 0
(-2850 3100);
PAINT MONO (-2850 3100);
DISPLAY INVISIBLE (-2850 3100);
FORCEPROP 1 LAST BODY_TYPE PLUMBING
J 2
(-2850 3050);
DISPLAY 1.595745 (-2850 3050);
PAINT GREEN (-2850 3050);
DISPLAY INVISIBLE (-2850 3050);
FORCEPROP 1 LAST HDL_TAP TRUE
J 2
(-3175 2975);
DISPLAY 1.595745 (-3175 2975);
PAINT GREEN (-3175 2975);
DISPLAY INVISIBLE (-3175 2975);
FORCEPROP 1 LAST PATH I130
J 2
(-2848 3100);
DISPLAY 0.872340 (-2848 3100);
PAINT GREEN (-2848 3100);
DISPLAY INVISIBLE (-2848 3100);
FORCEADD TAP..6
R 2
(-2850 3150);
FORCEPROP 3 LASTPIN (-2900 3150) SIG_NAME M_J_DQS_DN<6>
J 0
(-2890 3160);
DISPLAY 0.659574 (-2890 3160);
PAINT MONO (-2890 3160);
DISPLAY INVISIBLE (-2890 3160);
FORCEPROP 1 LASTPIN (-2900 3150) BN 6
J 2
(-2848 3158);
DISPLAY 0.617021 (-2848 3158);
PAINT GREEN (-2848 3158);
FORCEPROP 2 LAST CDS_LIB mstr_standard
J 0
(-2850 3150);
PAINT MONO (-2850 3150);
DISPLAY INVISIBLE (-2850 3150);
FORCEPROP 1 LAST BODY_TYPE PLUMBING
J 2
(-2850 3100);
DISPLAY 1.595745 (-2850 3100);
PAINT GREEN (-2850 3100);
DISPLAY INVISIBLE (-2850 3100);
FORCEPROP 1 LAST HDL_TAP TRUE
J 2
(-3175 3025);
DISPLAY 1.595745 (-3175 3025);
PAINT GREEN (-3175 3025);
DISPLAY INVISIBLE (-3175 3025);
FORCEPROP 1 LAST PATH I131
J 2
(-2848 3150);
DISPLAY 0.872340 (-2848 3150);
PAINT GREEN (-2848 3150);
DISPLAY INVISIBLE (-2848 3150);
FORCEADD TAP..6
R 2
(-2850 3200);
FORCEPROP 3 LASTPIN (-2900 3200) SIG_NAME M_J_DQS_DN<7>
J 0
(-2890 3210);
DISPLAY 0.659574 (-2890 3210);
PAINT MONO (-2890 3210);
DISPLAY INVISIBLE (-2890 3210);
FORCEPROP 1 LASTPIN (-2900 3200) BN 7
J 2
(-2848 3208);
DISPLAY 0.617021 (-2848 3208);
PAINT GREEN (-2848 3208);
FORCEPROP 2 LAST CDS_LIB mstr_standard
J 0
(-2850 3200);
PAINT MONO (-2850 3200);
DISPLAY INVISIBLE (-2850 3200);
FORCEPROP 1 LAST BODY_TYPE PLUMBING
J 2
(-2850 3150);
DISPLAY 1.595745 (-2850 3150);
PAINT GREEN (-2850 3150);
DISPLAY INVISIBLE (-2850 3150);
FORCEPROP 1 LAST HDL_TAP TRUE
J 2
(-3175 3075);
DISPLAY 1.595745 (-3175 3075);
PAINT GREEN (-3175 3075);
DISPLAY INVISIBLE (-3175 3075);
FORCEPROP 1 LAST PATH I132
J 2
(-2848 3200);
DISPLAY 0.872340 (-2848 3200);
PAINT GREEN (-2848 3200);
DISPLAY INVISIBLE (-2848 3200);
FORCEADD TAP..6
R 2
(-2850 3250);
FORCEPROP 3 LASTPIN (-2900 3250) SIG_NAME M_J_DQS_DN<8>
J 0
(-2890 3260);
DISPLAY 0.659574 (-2890 3260);
PAINT MONO (-2890 3260);
DISPLAY INVISIBLE (-2890 3260);
FORCEPROP 1 LASTPIN (-2900 3250) BN 8
J 2
(-2848 3258);
DISPLAY 0.617021 (-2848 3258);
PAINT GREEN (-2848 3258);
FORCEPROP 2 LAST CDS_LIB mstr_standard
J 0
(-2850 3250);
PAINT MONO (-2850 3250);
DISPLAY INVISIBLE (-2850 3250);
FORCEPROP 1 LAST BODY_TYPE PLUMBING
J 2
(-2850 3200);
DISPLAY 1.595745 (-2850 3200);
PAINT GREEN (-2850 3200);
DISPLAY INVISIBLE (-2850 3200);
FORCEPROP 1 LAST HDL_TAP TRUE
J 2
(-3175 3125);
DISPLAY 1.595745 (-3175 3125);
PAINT GREEN (-3175 3125);
DISPLAY INVISIBLE (-3175 3125);
FORCEPROP 1 LAST PATH I133
J 2
(-2848 3250);
DISPLAY 0.872340 (-2848 3250);
PAINT GREEN (-2848 3250);
DISPLAY INVISIBLE (-2848 3250);
FORCEADD TAP..6
R 2
(-2850 3300);
FORCEPROP 3 LASTPIN (-2900 3300) SIG_NAME M_J_DQS_DN<9>
J 0
(-2890 3310);
DISPLAY 0.659574 (-2890 3310);
PAINT MONO (-2890 3310);
DISPLAY INVISIBLE (-2890 3310);
FORCEPROP 1 LASTPIN (-2900 3300) BN 9
J 2
(-2848 3308);
DISPLAY 0.617021 (-2848 3308);
PAINT GREEN (-2848 3308);
FORCEPROP 2 LAST CDS_LIB mstr_standard
J 0
(-2850 3300);
PAINT MONO (-2850 3300);
DISPLAY INVISIBLE (-2850 3300);
FORCEPROP 1 LAST BODY_TYPE PLUMBING
J 2
(-2850 3250);
DISPLAY 1.595745 (-2850 3250);
PAINT GREEN (-2850 3250);
DISPLAY INVISIBLE (-2850 3250);
FORCEPROP 1 LAST HDL_TAP TRUE
J 2
(-3175 3175);
DISPLAY 1.595745 (-3175 3175);
PAINT GREEN (-3175 3175);
DISPLAY INVISIBLE (-3175 3175);
FORCEPROP 1 LAST PATH I134
J 2
(-2848 3300);
DISPLAY 0.872340 (-2848 3300);
PAINT GREEN (-2848 3300);
DISPLAY INVISIBLE (-2848 3300);
FORCEADD TAP..6
R 2
(-2850 3350);
FORCEPROP 3 LASTPIN (-2900 3350) SIG_NAME M_J_DQS_DN<10>
J 0
(-2890 3360);
DISPLAY 0.659574 (-2890 3360);
PAINT MONO (-2890 3360);
DISPLAY INVISIBLE (-2890 3360);
FORCEPROP 1 LASTPIN (-2900 3350) BN 10
J 2
(-2848 3358);
DISPLAY 0.617021 (-2848 3358);
PAINT GREEN (-2848 3358);
FORCEPROP 2 LAST CDS_LIB mstr_standard
J 0
(-2850 3350);
PAINT MONO (-2850 3350);
DISPLAY INVISIBLE (-2850 3350);
FORCEPROP 1 LAST BODY_TYPE PLUMBING
J 2
(-2850 3300);
DISPLAY 1.595745 (-2850 3300);
PAINT GREEN (-2850 3300);
DISPLAY INVISIBLE (-2850 3300);
FORCEPROP 1 LAST HDL_TAP TRUE
J 2
(-3175 3225);
DISPLAY 1.595745 (-3175 3225);
PAINT GREEN (-3175 3225);
DISPLAY INVISIBLE (-3175 3225);
FORCEPROP 1 LAST PATH I135
J 2
(-2848 3350);
DISPLAY 0.872340 (-2848 3350);
PAINT GREEN (-2848 3350);
DISPLAY INVISIBLE (-2848 3350);
FORCEADD TAP..6
R 2
(-2850 3450);
FORCEPROP 3 LASTPIN (-2900 3450) SIG_NAME M_J_DQS_DN<12>
J 0
(-2890 3460);
DISPLAY 0.659574 (-2890 3460);
PAINT MONO (-2890 3460);
DISPLAY INVISIBLE (-2890 3460);
FORCEPROP 1 LASTPIN (-2900 3450) BN 12
J 2
(-2848 3458);
DISPLAY 0.617021 (-2848 3458);
PAINT GREEN (-2848 3458);
FORCEPROP 2 LAST CDS_LIB mstr_standard
J 0
(-2850 3450);
PAINT MONO (-2850 3450);
DISPLAY INVISIBLE (-2850 3450);
FORCEPROP 1 LAST BODY_TYPE PLUMBING
J 2
(-2850 3400);
DISPLAY 1.595745 (-2850 3400);
PAINT GREEN (-2850 3400);
DISPLAY INVISIBLE (-2850 3400);
FORCEPROP 1 LAST HDL_TAP TRUE
J 2
(-3175 3325);
DISPLAY 1.595745 (-3175 3325);
PAINT GREEN (-3175 3325);
DISPLAY INVISIBLE (-3175 3325);
FORCEPROP 1 LAST PATH I136
J 2
(-2848 3450);
DISPLAY 0.872340 (-2848 3450);
PAINT GREEN (-2848 3450);
DISPLAY INVISIBLE (-2848 3450);
FORCEADD TAP..6
R 2
(-2850 3400);
FORCEPROP 3 LASTPIN (-2900 3400) SIG_NAME M_J_DQS_DN<11>
J 0
(-2890 3410);
DISPLAY 0.659574 (-2890 3410);
PAINT MONO (-2890 3410);
DISPLAY INVISIBLE (-2890 3410);
FORCEPROP 1 LASTPIN (-2900 3400) BN 11
J 2
(-2848 3408);
DISPLAY 0.617021 (-2848 3408);
PAINT GREEN (-2848 3408);
FORCEPROP 2 LAST CDS_LIB mstr_standard
J 0
(-2850 3400);
PAINT MONO (-2850 3400);
DISPLAY INVISIBLE (-2850 3400);
FORCEPROP 1 LAST BODY_TYPE PLUMBING
J 2
(-2850 3350);
DISPLAY 1.595745 (-2850 3350);
PAINT GREEN (-2850 3350);
DISPLAY INVISIBLE (-2850 3350);
FORCEPROP 1 LAST HDL_TAP TRUE
J 2
(-3175 3275);
DISPLAY 1.595745 (-3175 3275);
PAINT GREEN (-3175 3275);
DISPLAY INVISIBLE (-3175 3275);
FORCEPROP 1 LAST PATH I137
J 2
(-2848 3400);
DISPLAY 0.872340 (-2848 3400);
PAINT GREEN (-2848 3400);
DISPLAY INVISIBLE (-2848 3400);
FORCEADD TAP..6
R 2
(-2850 3600);
FORCEPROP 3 LASTPIN (-2900 3600) SIG_NAME M_J_DQS_DN<15>
J 0
(-2890 3610);
DISPLAY 0.659574 (-2890 3610);
PAINT MONO (-2890 3610);
DISPLAY INVISIBLE (-2890 3610);
FORCEPROP 1 LASTPIN (-2900 3600) BN 15
J 2
(-2848 3608);
DISPLAY 0.617021 (-2848 3608);
PAINT GREEN (-2848 3608);
FORCEPROP 2 LAST CDS_LIB mstr_standard
J 0
(-2850 3600);
PAINT MONO (-2850 3600);
DISPLAY INVISIBLE (-2850 3600);
FORCEPROP 1 LAST BODY_TYPE PLUMBING
J 2
(-2850 3550);
DISPLAY 1.595745 (-2850 3550);
PAINT GREEN (-2850 3550);
DISPLAY INVISIBLE (-2850 3550);
FORCEPROP 1 LAST HDL_TAP TRUE
J 2
(-3175 3475);
DISPLAY 1.595745 (-3175 3475);
PAINT GREEN (-3175 3475);
DISPLAY INVISIBLE (-3175 3475);
FORCEPROP 1 LAST PATH I138
J 2
(-2848 3600);
DISPLAY 0.872340 (-2848 3600);
PAINT GREEN (-2848 3600);
DISPLAY INVISIBLE (-2848 3600);
FORCEADD TAP..6
R 2
(-2850 3550);
FORCEPROP 3 LASTPIN (-2900 3550) SIG_NAME M_J_DQS_DN<14>
J 0
(-2890 3560);
DISPLAY 0.659574 (-2890 3560);
PAINT MONO (-2890 3560);
DISPLAY INVISIBLE (-2890 3560);
FORCEPROP 1 LASTPIN (-2900 3550) BN 14
J 2
(-2848 3558);
DISPLAY 0.617021 (-2848 3558);
PAINT GREEN (-2848 3558);
FORCEPROP 2 LAST CDS_LIB mstr_standard
J 0
(-2850 3550);
PAINT MONO (-2850 3550);
DISPLAY INVISIBLE (-2850 3550);
FORCEPROP 1 LAST BODY_TYPE PLUMBING
J 2
(-2850 3500);
DISPLAY 1.595745 (-2850 3500);
PAINT GREEN (-2850 3500);
DISPLAY INVISIBLE (-2850 3500);
FORCEPROP 1 LAST HDL_TAP TRUE
J 2
(-3175 3425);
DISPLAY 1.595745 (-3175 3425);
PAINT GREEN (-3175 3425);
DISPLAY INVISIBLE (-3175 3425);
FORCEPROP 1 LAST PATH I139
J 2
(-2848 3550);
DISPLAY 0.872340 (-2848 3550);
PAINT GREEN (-2848 3550);
DISPLAY INVISIBLE (-2848 3550);
FORCEADD TAP..6
(-5575 1100);
FORCEPROP 3 LASTPIN (-5525 1100) SIG_NAME M_J_ECC<1>
J 0
(-5515 1110);
DISPLAY 0.659574 (-5515 1110);
PAINT MONO (-5515 1110);
DISPLAY INVISIBLE (-5515 1110);
FORCEPROP 1 LASTPIN (-5525 1100) BN 1
J 0
(-5577 1108);
DISPLAY 0.617021 (-5577 1108);
PAINT GREEN (-5577 1108);
FORCEPROP 2 LAST CDS_LIB mstr_standard
J 0
(-5575 1100);
PAINT MONO (-5575 1100);
DISPLAY INVISIBLE (-5575 1100);
FORCEPROP 1 LAST BODY_TYPE PLUMBING
J 0
(-5575 1050);
DISPLAY 1.595745 (-5575 1050);
PAINT GREEN (-5575 1050);
DISPLAY INVISIBLE (-5575 1050);
FORCEPROP 1 LAST HDL_TAP TRUE
J 0
(-5250 975);
DISPLAY 1.595745 (-5250 975);
PAINT GREEN (-5250 975);
DISPLAY INVISIBLE (-5250 975);
FORCEPROP 1 LAST PATH I14
J 0
(-5577 1100);
DISPLAY 0.872340 (-5577 1100);
PAINT GREEN (-5577 1100);
DISPLAY INVISIBLE (-5577 1100);
FORCEADD TAP..6
R 2
(-2850 3500);
FORCEPROP 3 LASTPIN (-2900 3500) SIG_NAME M_J_DQS_DN<13>
J 0
(-2890 3510);
DISPLAY 0.659574 (-2890 3510);
PAINT MONO (-2890 3510);
DISPLAY INVISIBLE (-2890 3510);
FORCEPROP 1 LASTPIN (-2900 3500) BN 13
J 2
(-2848 3508);
DISPLAY 0.617021 (-2848 3508);
PAINT GREEN (-2848 3508);
FORCEPROP 2 LAST CDS_LIB mstr_standard
J 0
(-2850 3500);
PAINT MONO (-2850 3500);
DISPLAY INVISIBLE (-2850 3500);
FORCEPROP 1 LAST BODY_TYPE PLUMBING
J 2
(-2850 3450);
DISPLAY 1.595745 (-2850 3450);
PAINT GREEN (-2850 3450);
DISPLAY INVISIBLE (-2850 3450);
FORCEPROP 1 LAST HDL_TAP TRUE
J 2
(-3175 3375);
DISPLAY 1.595745 (-3175 3375);
PAINT GREEN (-3175 3375);
DISPLAY INVISIBLE (-3175 3375);
FORCEPROP 1 LAST PATH I140
J 2
(-2848 3500);
DISPLAY 0.872340 (-2848 3500);
PAINT GREEN (-2848 3500);
DISPLAY INVISIBLE (-2848 3500);
FORCEADD TAP..6
R 2
(-2850 3650);
FORCEPROP 3 LASTPIN (-2900 3650) SIG_NAME M_J_DQS_DN<16>
J 0
(-2890 3660);
DISPLAY 0.659574 (-2890 3660);
PAINT MONO (-2890 3660);
DISPLAY INVISIBLE (-2890 3660);
FORCEPROP 1 LASTPIN (-2900 3650) BN 16
J 2
(-2848 3658);
DISPLAY 0.617021 (-2848 3658);
PAINT GREEN (-2848 3658);
FORCEPROP 2 LAST CDS_LIB mstr_standard
J 0
(-2850 3650);
PAINT MONO (-2850 3650);
DISPLAY INVISIBLE (-2850 3650);
FORCEPROP 1 LAST BODY_TYPE PLUMBING
J 2
(-2850 3600);
DISPLAY 1.595745 (-2850 3600);
PAINT GREEN (-2850 3600);
DISPLAY INVISIBLE (-2850 3600);
FORCEPROP 1 LAST HDL_TAP TRUE
J 2
(-3175 3525);
DISPLAY 1.595745 (-3175 3525);
PAINT GREEN (-3175 3525);
DISPLAY INVISIBLE (-3175 3525);
FORCEPROP 1 LAST PATH I141
J 2
(-2848 3650);
DISPLAY 0.872340 (-2848 3650);
PAINT GREEN (-2848 3650);
DISPLAY INVISIBLE (-2848 3650);
FORCEADD TAP..6
R 2
(-2850 3700);
FORCEPROP 3 LASTPIN (-2900 3700) SIG_NAME M_J_DQS_DN<17>
J 0
(-2890 3710);
DISPLAY 0.659574 (-2890 3710);
PAINT MONO (-2890 3710);
DISPLAY INVISIBLE (-2890 3710);
FORCEPROP 1 LASTPIN (-2900 3700) BN 17
J 2
(-2848 3708);
DISPLAY 0.617021 (-2848 3708);
PAINT GREEN (-2848 3708);
FORCEPROP 2 LAST CDS_LIB mstr_standard
J 0
(-2850 3700);
PAINT MONO (-2850 3700);
DISPLAY INVISIBLE (-2850 3700);
FORCEPROP 1 LAST BODY_TYPE PLUMBING
J 2
(-2850 3650);
DISPLAY 1.595745 (-2850 3650);
PAINT GREEN (-2850 3650);
DISPLAY INVISIBLE (-2850 3650);
FORCEPROP 1 LAST HDL_TAP TRUE
J 2
(-3175 3575);
DISPLAY 1.595745 (-3175 3575);
PAINT GREEN (-3175 3575);
DISPLAY INVISIBLE (-3175 3575);
FORCEPROP 1 LAST PATH I142
J 2
(-2848 3700);
DISPLAY 0.872340 (-2848 3700);
PAINT GREEN (-2848 3700);
DISPLAY INVISIBLE (-2848 3700);
FORCEADD TAP..6
R 2
(-2850 3800);
FORCEPROP 3 LASTPIN (-2900 3800) SIG_NAME M_J_DQS_DP<0>
J 0
(-2890 3810);
DISPLAY 0.659574 (-2890 3810);
PAINT MONO (-2890 3810);
DISPLAY INVISIBLE (-2890 3810);
FORCEPROP 1 LASTPIN (-2900 3800) BN 0
J 2
(-2848 3808);
DISPLAY 0.617021 (-2848 3808);
PAINT GREEN (-2848 3808);
FORCEPROP 2 LAST CDS_LIB mstr_standard
J 0
(-2850 3800);
PAINT MONO (-2850 3800);
DISPLAY INVISIBLE (-2850 3800);
FORCEPROP 1 LAST BODY_TYPE PLUMBING
J 2
(-2850 3750);
DISPLAY 1.595745 (-2850 3750);
PAINT GREEN (-2850 3750);
DISPLAY INVISIBLE (-2850 3750);
FORCEPROP 1 LAST HDL_TAP TRUE
J 2
(-3175 3675);
DISPLAY 1.595745 (-3175 3675);
PAINT GREEN (-3175 3675);
DISPLAY INVISIBLE (-3175 3675);
FORCEPROP 1 LAST PATH I143
J 2
(-2848 3800);
DISPLAY 0.872340 (-2848 3800);
PAINT GREEN (-2848 3800);
DISPLAY INVISIBLE (-2848 3800);
FORCEADD TAP..6
R 2
(-2850 3850);
FORCEPROP 3 LASTPIN (-2900 3850) SIG_NAME M_J_DQS_DP<1>
J 0
(-2890 3860);
DISPLAY 0.659574 (-2890 3860);
PAINT MONO (-2890 3860);
DISPLAY INVISIBLE (-2890 3860);
FORCEPROP 1 LASTPIN (-2900 3850) BN 1
J 2
(-2848 3858);
DISPLAY 0.617021 (-2848 3858);
PAINT GREEN (-2848 3858);
FORCEPROP 2 LAST CDS_LIB mstr_standard
J 0
(-2850 3850);
PAINT MONO (-2850 3850);
DISPLAY INVISIBLE (-2850 3850);
FORCEPROP 1 LAST BODY_TYPE PLUMBING
J 2
(-2850 3800);
DISPLAY 1.595745 (-2850 3800);
PAINT GREEN (-2850 3800);
DISPLAY INVISIBLE (-2850 3800);
FORCEPROP 1 LAST HDL_TAP TRUE
J 2
(-3175 3725);
DISPLAY 1.595745 (-3175 3725);
PAINT GREEN (-3175 3725);
DISPLAY INVISIBLE (-3175 3725);
FORCEPROP 1 LAST PATH I144
J 2
(-2848 3850);
DISPLAY 0.872340 (-2848 3850);
PAINT GREEN (-2848 3850);
DISPLAY INVISIBLE (-2848 3850);
FORCEADD TAP..6
R 2
(-2850 3900);
FORCEPROP 3 LASTPIN (-2900 3900) SIG_NAME M_J_DQS_DP<2>
J 0
(-2890 3910);
DISPLAY 0.659574 (-2890 3910);
PAINT MONO (-2890 3910);
DISPLAY INVISIBLE (-2890 3910);
FORCEPROP 1 LASTPIN (-2900 3900) BN 2
J 2
(-2848 3908);
DISPLAY 0.617021 (-2848 3908);
PAINT GREEN (-2848 3908);
FORCEPROP 2 LAST CDS_LIB mstr_standard
J 0
(-2850 3900);
PAINT MONO (-2850 3900);
DISPLAY INVISIBLE (-2850 3900);
FORCEPROP 1 LAST BODY_TYPE PLUMBING
J 2
(-2850 3850);
DISPLAY 1.595745 (-2850 3850);
PAINT GREEN (-2850 3850);
DISPLAY INVISIBLE (-2850 3850);
FORCEPROP 1 LAST HDL_TAP TRUE
J 2
(-3175 3775);
DISPLAY 1.595745 (-3175 3775);
PAINT GREEN (-3175 3775);
DISPLAY INVISIBLE (-3175 3775);
FORCEPROP 1 LAST PATH I145
J 2
(-2848 3900);
DISPLAY 0.872340 (-2848 3900);
PAINT GREEN (-2848 3900);
DISPLAY INVISIBLE (-2848 3900);
FORCEADD TAP..6
R 2
(-2850 3950);
FORCEPROP 3 LASTPIN (-2900 3950) SIG_NAME M_J_DQS_DP<3>
J 0
(-2890 3960);
DISPLAY 0.659574 (-2890 3960);
PAINT MONO (-2890 3960);
DISPLAY INVISIBLE (-2890 3960);
FORCEPROP 1 LASTPIN (-2900 3950) BN 3
J 2
(-2848 3958);
DISPLAY 0.617021 (-2848 3958);
PAINT GREEN (-2848 3958);
FORCEPROP 2 LAST CDS_LIB mstr_standard
J 0
(-2850 3950);
PAINT MONO (-2850 3950);
DISPLAY INVISIBLE (-2850 3950);
FORCEPROP 1 LAST BODY_TYPE PLUMBING
J 2
(-2850 3900);
DISPLAY 1.595745 (-2850 3900);
PAINT GREEN (-2850 3900);
DISPLAY INVISIBLE (-2850 3900);
FORCEPROP 1 LAST HDL_TAP TRUE
J 2
(-3175 3825);
DISPLAY 1.595745 (-3175 3825);
PAINT GREEN (-3175 3825);
DISPLAY INVISIBLE (-3175 3825);
FORCEPROP 1 LAST PATH I146
J 2
(-2848 3950);
DISPLAY 0.872340 (-2848 3950);
PAINT GREEN (-2848 3950);
DISPLAY INVISIBLE (-2848 3950);
FORCEADD OFFPAGE..2
(-1975 500);
FORCEPROP 2 LAST $XR0 81 
J 0
(-1786 500);
DISPLAY 0.638298 (-1786 500);
PAINT MONO (-1786 500);
FORCEPROP 2 LAST $XR1 82 
J 0
(-1696 500);
DISPLAY 0.638298 (-1696 500);
PAINT MONO (-1696 500);
FORCEPROP 2 LAST CDS_LIB mstr_standard
J 0
(-1975 500);
PAINT MONO (-1975 500);
DISPLAY INVISIBLE (-1975 500);
FORCEPROP 1 LAST OFFPAGE TRUE
J 0
(-1650 375);
DISPLAY 1.170213 (-1650 375);
PAINT GREEN (-1650 375);
DISPLAY INVISIBLE (-1650 375);
FORCEPROP 1 LAST COMMENT_BODY TRUE
J 0
(-2020 405);
DISPLAY 1.170213 (-2020 405);
PAINT GREEN (-2020 405);
DISPLAY INVISIBLE (-2020 405);
FORCEPROP 2 LAST PATH I147
J 0
(-1800 575);
DISPLAY 1.021277 (-1800 575);
PAINT ORANGE (-1800 575);
DISPLAY INVISIBLE (-1800 575);
FORCEADD OFFPAGE..4
(-1975 550);
FORCEPROP 2 LAST $XR0 81 
J 0
(-1789 550);
DISPLAY 0.638298 (-1789 550);
PAINT MONO (-1789 550);
FORCEPROP 2 LAST $XR1 82 
J 0
(-1699 550);
DISPLAY 0.638298 (-1699 550);
PAINT MONO (-1699 550);
FORCEPROP 2 LAST CDS_LIB mstr_standard
J 0
(-1975 550);
PAINT MONO (-1975 550);
DISPLAY INVISIBLE (-1975 550);
FORCEPROP 1 LAST OFFPAGE TRUE
J 0
(-1650 425);
DISPLAY 1.170213 (-1650 425);
PAINT GREEN (-1650 425);
DISPLAY INVISIBLE (-1650 425);
FORCEPROP 1 LAST COMMENT_BODY TRUE
J 0
(-2000 450);
DISPLAY 1.170213 (-2000 450);
PAINT GREEN (-2000 450);
DISPLAY INVISIBLE (-2000 450);
FORCEPROP 2 LAST PATH I148
J 0
(-1800 625);
DISPLAY 1.021277 (-1800 625);
PAINT ORANGE (-1800 625);
DISPLAY INVISIBLE (-1800 625);
FORCEADD OFFPAGE..2
(-1975 600);
FORCEPROP 2 LAST $XR0 81 
J 0
(-1786 600);
DISPLAY 0.638298 (-1786 600);
PAINT MONO (-1786 600);
FORCEPROP 2 LAST $XR1 82 
J 0
(-1696 600);
DISPLAY 0.638298 (-1696 600);
PAINT MONO (-1696 600);
FORCEPROP 2 LAST CDS_LIB mstr_standard
J 0
(-1975 600);
PAINT MONO (-1975 600);
DISPLAY INVISIBLE (-1975 600);
FORCEPROP 1 LAST OFFPAGE TRUE
J 0
(-1650 475);
DISPLAY 1.170213 (-1650 475);
PAINT GREEN (-1650 475);
DISPLAY INVISIBLE (-1650 475);
FORCEPROP 1 LAST COMMENT_BODY TRUE
J 0
(-2020 505);
DISPLAY 1.170213 (-2020 505);
PAINT GREEN (-2020 505);
DISPLAY INVISIBLE (-2020 505);
FORCEPROP 2 LAST PATH I149
J 0
(-1800 675);
DISPLAY 1.021277 (-1800 675);
PAINT ORANGE (-1800 675);
DISPLAY INVISIBLE (-1800 675);
FORCEADD TAP..6
(-5575 1150);
FORCEPROP 3 LASTPIN (-5525 1150) SIG_NAME M_J_ECC<2>
J 0
(-5515 1160);
DISPLAY 0.659574 (-5515 1160);
PAINT MONO (-5515 1160);
DISPLAY INVISIBLE (-5515 1160);
FORCEPROP 1 LASTPIN (-5525 1150) BN 2
J 0
(-5577 1158);
DISPLAY 0.617021 (-5577 1158);
PAINT GREEN (-5577 1158);
FORCEPROP 2 LAST CDS_LIB mstr_standard
J 0
(-5575 1150);
PAINT MONO (-5575 1150);
DISPLAY INVISIBLE (-5575 1150);
FORCEPROP 1 LAST BODY_TYPE PLUMBING
J 0
(-5575 1100);
DISPLAY 1.595745 (-5575 1100);
PAINT GREEN (-5575 1100);
DISPLAY INVISIBLE (-5575 1100);
FORCEPROP 1 LAST HDL_TAP TRUE
J 0
(-5250 1025);
DISPLAY 1.595745 (-5250 1025);
PAINT GREEN (-5250 1025);
DISPLAY INVISIBLE (-5250 1025);
FORCEPROP 1 LAST PATH I15
J 0
(-5577 1150);
DISPLAY 0.872340 (-5577 1150);
PAINT GREEN (-5577 1150);
DISPLAY INVISIBLE (-5577 1150);
FORCEADD OFFPAGE..2
(-2000 800);
FORCEPROP 2 LAST $XR0 81 
J 0
(-1811 800);
DISPLAY 0.638298 (-1811 800);
PAINT MONO (-1811 800);
FORCEPROP 2 LAST $XR1 82 
J 0
(-1721 800);
DISPLAY 0.638298 (-1721 800);
PAINT MONO (-1721 800);
FORCEPROP 2 LAST CDS_LIB mstr_standard
J 0
(-2000 800);
PAINT MONO (-2000 800);
DISPLAY INVISIBLE (-2000 800);
FORCEPROP 1 LAST OFFPAGE TRUE
J 0
(-1675 675);
DISPLAY 1.170213 (-1675 675);
PAINT GREEN (-1675 675);
DISPLAY INVISIBLE (-1675 675);
FORCEPROP 1 LAST COMMENT_BODY TRUE
J 0
(-2045 705);
DISPLAY 1.170213 (-2045 705);
PAINT GREEN (-2045 705);
DISPLAY INVISIBLE (-2045 705);
FORCEPROP 2 LAST PATH I150
J 0
(-1825 875);
DISPLAY 1.021277 (-1825 875);
PAINT ORANGE (-1825 875);
DISPLAY INVISIBLE (-1825 875);
FORCEADD OFFPAGE..2
(-2000 900);
FORCEPROP 2 LAST $XR0 81 
J 0
(-1811 900);
DISPLAY 0.638298 (-1811 900);
PAINT MONO (-1811 900);
FORCEPROP 2 LAST $XR1 82 
J 0
(-1721 900);
DISPLAY 0.638298 (-1721 900);
PAINT MONO (-1721 900);
FORCEPROP 2 LAST CDS_LIB mstr_standard
J 0
(-2000 900);
PAINT MONO (-2000 900);
DISPLAY INVISIBLE (-2000 900);
FORCEPROP 1 LAST OFFPAGE TRUE
J 0
(-1675 775);
DISPLAY 1.170213 (-1675 775);
PAINT GREEN (-1675 775);
DISPLAY INVISIBLE (-1675 775);
FORCEPROP 1 LAST COMMENT_BODY TRUE
J 0
(-2045 805);
DISPLAY 1.170213 (-2045 805);
PAINT GREEN (-2045 805);
DISPLAY INVISIBLE (-2045 805);
FORCEPROP 2 LAST PATH I151
J 0
(-1825 975);
DISPLAY 1.021277 (-1825 975);
PAINT ORANGE (-1825 975);
DISPLAY INVISIBLE (-1825 975);
FORCEADD OFFPAGE..2
(-2000 1350);
FORCEPROP 2 LAST $XR0 81 
J 0
(-1811 1350);
DISPLAY 0.638298 (-1811 1350);
PAINT MONO (-1811 1350);
FORCEPROP 2 LAST $XR1 82 
J 0
(-1721 1350);
DISPLAY 0.638298 (-1721 1350);
PAINT MONO (-1721 1350);
FORCEPROP 2 LAST CDS_LIB mstr_standard
J 0
(-2000 1350);
PAINT MONO (-2000 1350);
DISPLAY INVISIBLE (-2000 1350);
FORCEPROP 1 LAST OFFPAGE TRUE
J 0
(-1675 1225);
DISPLAY 1.170213 (-1675 1225);
PAINT GREEN (-1675 1225);
DISPLAY INVISIBLE (-1675 1225);
FORCEPROP 1 LAST COMMENT_BODY TRUE
J 0
(-2045 1255);
DISPLAY 1.170213 (-2045 1255);
PAINT GREEN (-2045 1255);
DISPLAY INVISIBLE (-2045 1255);
FORCEPROP 2 LAST PATH I152
J 0
(-1825 1425);
DISPLAY 1.021277 (-1825 1425);
PAINT ORANGE (-1825 1425);
DISPLAY INVISIBLE (-1825 1425);
FORCEADD OFFPAGE..2
(-2000 1600);
FORCEPROP 2 LAST $XR0 81 
J 0
(-1811 1600);
DISPLAY 0.638298 (-1811 1600);
PAINT MONO (-1811 1600);
FORCEPROP 2 LAST $XR1 82 
J 0
(-1721 1600);
DISPLAY 0.638298 (-1721 1600);
PAINT MONO (-1721 1600);
FORCEPROP 2 LAST CDS_LIB mstr_standard
J 0
(-2000 1600);
PAINT MONO (-2000 1600);
DISPLAY INVISIBLE (-2000 1600);
FORCEPROP 1 LAST OFFPAGE TRUE
J 0
(-1675 1475);
DISPLAY 1.170213 (-1675 1475);
PAINT GREEN (-1675 1475);
DISPLAY INVISIBLE (-1675 1475);
FORCEPROP 1 LAST COMMENT_BODY TRUE
J 0
(-2045 1505);
DISPLAY 1.170213 (-2045 1505);
PAINT GREEN (-2045 1505);
DISPLAY INVISIBLE (-2045 1505);
FORCEPROP 2 LAST PATH I153
J 0
(-1825 1675);
DISPLAY 1.021277 (-1825 1675);
PAINT ORANGE (-1825 1675);
DISPLAY INVISIBLE (-1825 1675);
FORCEADD OFFPAGE..2
(-2000 1850);
FORCEPROP 2 LAST $XR0 81 
J 0
(-1811 1850);
DISPLAY 0.638298 (-1811 1850);
PAINT MONO (-1811 1850);
FORCEPROP 2 LAST $XR1 82 
J 0
(-1721 1850);
DISPLAY 0.638298 (-1721 1850);
PAINT MONO (-1721 1850);
FORCEPROP 2 LAST CDS_LIB mstr_standard
J 0
(-2000 1850);
PAINT MONO (-2000 1850);
DISPLAY INVISIBLE (-2000 1850);
FORCEPROP 1 LAST OFFPAGE TRUE
J 0
(-1675 1725);
DISPLAY 1.170213 (-1675 1725);
PAINT GREEN (-1675 1725);
DISPLAY INVISIBLE (-1675 1725);
FORCEPROP 1 LAST COMMENT_BODY TRUE
J 0
(-2045 1755);
DISPLAY 1.170213 (-2045 1755);
PAINT GREEN (-2045 1755);
DISPLAY INVISIBLE (-2045 1755);
FORCEPROP 2 LAST PATH I154
J 0
(-1825 1925);
DISPLAY 1.021277 (-1825 1925);
PAINT ORANGE (-1825 1925);
DISPLAY INVISIBLE (-1825 1925);
FORCEADD OFFPAGE..2
(-2000 2800);
FORCEPROP 2 LAST $XR0 81 
J 0
(-1811 2800);
DISPLAY 0.638298 (-1811 2800);
PAINT MONO (-1811 2800);
FORCEPROP 2 LAST $XR1 82 
J 0
(-1721 2800);
DISPLAY 0.638298 (-1721 2800);
PAINT MONO (-1721 2800);
FORCEPROP 2 LAST CDS_LIB mstr_standard
J 0
(-2000 2800);
PAINT MONO (-2000 2800);
DISPLAY INVISIBLE (-2000 2800);
FORCEPROP 1 LAST OFFPAGE TRUE
J 0
(-1675 2675);
DISPLAY 1.170213 (-1675 2675);
PAINT GREEN (-1675 2675);
DISPLAY INVISIBLE (-1675 2675);
FORCEPROP 1 LAST COMMENT_BODY TRUE
J 0
(-2045 2705);
DISPLAY 1.170213 (-2045 2705);
PAINT GREEN (-2045 2705);
DISPLAY INVISIBLE (-2045 2705);
FORCEPROP 2 LAST PATH I155
J 0
(-1825 2875);
DISPLAY 1.021277 (-1825 2875);
PAINT ORANGE (-1825 2875);
DISPLAY INVISIBLE (-1825 2875);
FORCEADD OFFPAGE..3
(-2000 3750);
FORCEPROP 2 LAST $XR0 81 
J 0
(-1786 3750);
DISPLAY 0.638298 (-1786 3750);
PAINT MONO (-1786 3750);
FORCEPROP 2 LAST $XR1 82 
J 0
(-1696 3750);
DISPLAY 0.638298 (-1696 3750);
PAINT MONO (-1696 3750);
FORCEPROP 2 LAST CDS_LIB mstr_standard
J 0
(-2000 3750);
PAINT MONO (-2000 3750);
DISPLAY INVISIBLE (-2000 3750);
FORCEPROP 1 LAST OFFPAGE TRUE
J 0
(-1675 3625);
DISPLAY 1.170213 (-1675 3625);
PAINT GREEN (-1675 3625);
DISPLAY INVISIBLE (-1675 3625);
FORCEPROP 1 LAST COMMENT_BODY TRUE
J 0
(-2050 3650);
DISPLAY 1.170213 (-2050 3650);
PAINT GREEN (-2050 3650);
DISPLAY INVISIBLE (-2050 3650);
FORCEPROP 2 LAST PATH I156
J 0
(-1800 3825);
DISPLAY 1.021277 (-1800 3825);
PAINT ORANGE (-1800 3825);
DISPLAY INVISIBLE (-1800 3825);
FORCEADD TAP..6
R 2
(-2850 4000);
FORCEPROP 3 LASTPIN (-2900 4000) SIG_NAME M_J_DQS_DP<4>
J 0
(-2890 4010);
DISPLAY 0.659574 (-2890 4010);
PAINT MONO (-2890 4010);
DISPLAY INVISIBLE (-2890 4010);
FORCEPROP 1 LASTPIN (-2900 4000) BN 4
J 2
(-2848 4008);
DISPLAY 0.617021 (-2848 4008);
PAINT GREEN (-2848 4008);
FORCEPROP 2 LAST CDS_LIB mstr_standard
J 0
(-2850 4000);
PAINT MONO (-2850 4000);
DISPLAY INVISIBLE (-2850 4000);
FORCEPROP 1 LAST BODY_TYPE PLUMBING
J 2
(-2850 3950);
DISPLAY 1.595745 (-2850 3950);
PAINT GREEN (-2850 3950);
DISPLAY INVISIBLE (-2850 3950);
FORCEPROP 1 LAST HDL_TAP TRUE
J 2
(-3175 3875);
DISPLAY 1.595745 (-3175 3875);
PAINT GREEN (-3175 3875);
DISPLAY INVISIBLE (-3175 3875);
FORCEPROP 1 LAST PATH I157
J 2
(-2848 4000);
DISPLAY 0.872340 (-2848 4000);
PAINT GREEN (-2848 4000);
DISPLAY INVISIBLE (-2848 4000);
FORCEADD TAP..6
R 2
(-2850 4100);
FORCEPROP 3 LASTPIN (-2900 4100) SIG_NAME M_J_DQS_DP<6>
J 0
(-2890 4110);
DISPLAY 0.659574 (-2890 4110);
PAINT MONO (-2890 4110);
DISPLAY INVISIBLE (-2890 4110);
FORCEPROP 1 LASTPIN (-2900 4100) BN 6
J 2
(-2848 4108);
DISPLAY 0.617021 (-2848 4108);
PAINT GREEN (-2848 4108);
FORCEPROP 2 LAST CDS_LIB mstr_standard
J 0
(-2850 4100);
PAINT MONO (-2850 4100);
DISPLAY INVISIBLE (-2850 4100);
FORCEPROP 1 LAST BODY_TYPE PLUMBING
J 2
(-2850 4050);
DISPLAY 1.595745 (-2850 4050);
PAINT GREEN (-2850 4050);
DISPLAY INVISIBLE (-2850 4050);
FORCEPROP 1 LAST HDL_TAP TRUE
J 2
(-3175 3975);
DISPLAY 1.595745 (-3175 3975);
PAINT GREEN (-3175 3975);
DISPLAY INVISIBLE (-3175 3975);
FORCEPROP 1 LAST PATH I158
J 2
(-2848 4100);
DISPLAY 0.872340 (-2848 4100);
PAINT GREEN (-2848 4100);
DISPLAY INVISIBLE (-2848 4100);
FORCEADD TAP..6
R 2
(-2850 4050);
FORCEPROP 3 LASTPIN (-2900 4050) SIG_NAME M_J_DQS_DP<5>
J 0
(-2890 4060);
DISPLAY 0.659574 (-2890 4060);
PAINT MONO (-2890 4060);
DISPLAY INVISIBLE (-2890 4060);
FORCEPROP 1 LASTPIN (-2900 4050) BN 5
J 2
(-2848 4058);
DISPLAY 0.617021 (-2848 4058);
PAINT GREEN (-2848 4058);
FORCEPROP 2 LAST CDS_LIB mstr_standard
J 0
(-2850 4050);
PAINT MONO (-2850 4050);
DISPLAY INVISIBLE (-2850 4050);
FORCEPROP 1 LAST BODY_TYPE PLUMBING
J 2
(-2850 4000);
DISPLAY 1.595745 (-2850 4000);
PAINT GREEN (-2850 4000);
DISPLAY INVISIBLE (-2850 4000);
FORCEPROP 1 LAST HDL_TAP TRUE
J 2
(-3175 3925);
DISPLAY 1.595745 (-3175 3925);
PAINT GREEN (-3175 3925);
DISPLAY INVISIBLE (-3175 3925);
FORCEPROP 1 LAST PATH I159
J 2
(-2848 4050);
DISPLAY 0.872340 (-2848 4050);
PAINT GREEN (-2848 4050);
DISPLAY INVISIBLE (-2848 4050);
FORCEADD TAP..6
(-5575 1250);
FORCEPROP 3 LASTPIN (-5525 1250) SIG_NAME M_J_ECC<4>
J 0
(-5515 1260);
DISPLAY 0.659574 (-5515 1260);
PAINT MONO (-5515 1260);
DISPLAY INVISIBLE (-5515 1260);
FORCEPROP 1 LASTPIN (-5525 1250) BN 4
J 0
(-5577 1258);
DISPLAY 0.617021 (-5577 1258);
PAINT GREEN (-5577 1258);
FORCEPROP 2 LAST CDS_LIB mstr_standard
J 0
(-5575 1250);
PAINT MONO (-5575 1250);
DISPLAY INVISIBLE (-5575 1250);
FORCEPROP 1 LAST BODY_TYPE PLUMBING
J 0
(-5575 1200);
DISPLAY 1.595745 (-5575 1200);
PAINT GREEN (-5575 1200);
DISPLAY INVISIBLE (-5575 1200);
FORCEPROP 1 LAST HDL_TAP TRUE
J 0
(-5250 1125);
DISPLAY 1.595745 (-5250 1125);
PAINT GREEN (-5250 1125);
DISPLAY INVISIBLE (-5250 1125);
FORCEPROP 1 LAST PATH I16
J 0
(-5577 1250);
DISPLAY 0.872340 (-5577 1250);
PAINT GREEN (-5577 1250);
DISPLAY INVISIBLE (-5577 1250);
FORCEADD TAP..6
R 2
(-2850 4150);
FORCEPROP 3 LASTPIN (-2900 4150) SIG_NAME M_J_DQS_DP<7>
J 0
(-2890 4160);
DISPLAY 0.659574 (-2890 4160);
PAINT MONO (-2890 4160);
DISPLAY INVISIBLE (-2890 4160);
FORCEPROP 1 LASTPIN (-2900 4150) BN 7
J 2
(-2848 4158);
DISPLAY 0.617021 (-2848 4158);
PAINT GREEN (-2848 4158);
FORCEPROP 2 LAST CDS_LIB mstr_standard
J 0
(-2850 4150);
PAINT MONO (-2850 4150);
DISPLAY INVISIBLE (-2850 4150);
FORCEPROP 1 LAST BODY_TYPE PLUMBING
J 2
(-2850 4100);
DISPLAY 1.595745 (-2850 4100);
PAINT GREEN (-2850 4100);
DISPLAY INVISIBLE (-2850 4100);
FORCEPROP 1 LAST HDL_TAP TRUE
J 2
(-3175 4025);
DISPLAY 1.595745 (-3175 4025);
PAINT GREEN (-3175 4025);
DISPLAY INVISIBLE (-3175 4025);
FORCEPROP 1 LAST PATH I160
J 2
(-2848 4150);
DISPLAY 0.872340 (-2848 4150);
PAINT GREEN (-2848 4150);
DISPLAY INVISIBLE (-2848 4150);
FORCEADD TAP..6
R 2
(-2850 4200);
FORCEPROP 3 LASTPIN (-2900 4200) SIG_NAME M_J_DQS_DP<8>
J 0
(-2890 4210);
DISPLAY 0.659574 (-2890 4210);
PAINT MONO (-2890 4210);
DISPLAY INVISIBLE (-2890 4210);
FORCEPROP 1 LASTPIN (-2900 4200) BN 8
J 2
(-2848 4208);
DISPLAY 0.617021 (-2848 4208);
PAINT GREEN (-2848 4208);
FORCEPROP 2 LAST CDS_LIB mstr_standard
J 0
(-2850 4200);
PAINT MONO (-2850 4200);
DISPLAY INVISIBLE (-2850 4200);
FORCEPROP 1 LAST BODY_TYPE PLUMBING
J 2
(-2850 4150);
DISPLAY 1.595745 (-2850 4150);
PAINT GREEN (-2850 4150);
DISPLAY INVISIBLE (-2850 4150);
FORCEPROP 1 LAST HDL_TAP TRUE
J 2
(-3175 4075);
DISPLAY 1.595745 (-3175 4075);
PAINT GREEN (-3175 4075);
DISPLAY INVISIBLE (-3175 4075);
FORCEPROP 1 LAST PATH I161
J 2
(-2848 4200);
DISPLAY 0.872340 (-2848 4200);
PAINT GREEN (-2848 4200);
DISPLAY INVISIBLE (-2848 4200);
FORCEADD TAP..6
R 2
(-2850 4250);
FORCEPROP 3 LASTPIN (-2900 4250) SIG_NAME M_J_DQS_DP<9>
J 0
(-2890 4260);
DISPLAY 0.659574 (-2890 4260);
PAINT MONO (-2890 4260);
DISPLAY INVISIBLE (-2890 4260);
FORCEPROP 1 LASTPIN (-2900 4250) BN 9
J 2
(-2848 4258);
DISPLAY 0.617021 (-2848 4258);
PAINT GREEN (-2848 4258);
FORCEPROP 2 LAST CDS_LIB mstr_standard
J 0
(-2850 4250);
PAINT MONO (-2850 4250);
DISPLAY INVISIBLE (-2850 4250);
FORCEPROP 1 LAST BODY_TYPE PLUMBING
J 2
(-2850 4200);
DISPLAY 1.595745 (-2850 4200);
PAINT GREEN (-2850 4200);
DISPLAY INVISIBLE (-2850 4200);
FORCEPROP 1 LAST HDL_TAP TRUE
J 2
(-3175 4125);
DISPLAY 1.595745 (-3175 4125);
PAINT GREEN (-3175 4125);
DISPLAY INVISIBLE (-3175 4125);
FORCEPROP 1 LAST PATH I162
J 2
(-2848 4250);
DISPLAY 0.872340 (-2848 4250);
PAINT GREEN (-2848 4250);
DISPLAY INVISIBLE (-2848 4250);
FORCEADD TAP..6
R 2
(-2850 4300);
FORCEPROP 3 LASTPIN (-2900 4300) SIG_NAME M_J_DQS_DP<10>
J 0
(-2890 4310);
DISPLAY 0.659574 (-2890 4310);
PAINT MONO (-2890 4310);
DISPLAY INVISIBLE (-2890 4310);
FORCEPROP 1 LASTPIN (-2900 4300) BN 10
J 2
(-2848 4308);
DISPLAY 0.617021 (-2848 4308);
PAINT GREEN (-2848 4308);
FORCEPROP 2 LAST CDS_LIB mstr_standard
J 0
(-2850 4300);
PAINT MONO (-2850 4300);
DISPLAY INVISIBLE (-2850 4300);
FORCEPROP 1 LAST BODY_TYPE PLUMBING
J 2
(-2850 4250);
DISPLAY 1.595745 (-2850 4250);
PAINT GREEN (-2850 4250);
DISPLAY INVISIBLE (-2850 4250);
FORCEPROP 1 LAST HDL_TAP TRUE
J 2
(-3175 4175);
DISPLAY 1.595745 (-3175 4175);
PAINT GREEN (-3175 4175);
DISPLAY INVISIBLE (-3175 4175);
FORCEPROP 1 LAST PATH I163
J 2
(-2848 4300);
DISPLAY 0.872340 (-2848 4300);
PAINT GREEN (-2848 4300);
DISPLAY INVISIBLE (-2848 4300);
FORCEADD TAP..6
R 2
(-2850 4350);
FORCEPROP 3 LASTPIN (-2900 4350) SIG_NAME M_J_DQS_DP<11>
J 0
(-2890 4360);
DISPLAY 0.659574 (-2890 4360);
PAINT MONO (-2890 4360);
DISPLAY INVISIBLE (-2890 4360);
FORCEPROP 1 LASTPIN (-2900 4350) BN 11
J 2
(-2848 4358);
DISPLAY 0.617021 (-2848 4358);
PAINT GREEN (-2848 4358);
FORCEPROP 2 LAST CDS_LIB mstr_standard
J 0
(-2850 4350);
PAINT MONO (-2850 4350);
DISPLAY INVISIBLE (-2850 4350);
FORCEPROP 1 LAST BODY_TYPE PLUMBING
J 2
(-2850 4300);
DISPLAY 1.595745 (-2850 4300);
PAINT GREEN (-2850 4300);
DISPLAY INVISIBLE (-2850 4300);
FORCEPROP 1 LAST HDL_TAP TRUE
J 2
(-3175 4225);
DISPLAY 1.595745 (-3175 4225);
PAINT GREEN (-3175 4225);
DISPLAY INVISIBLE (-3175 4225);
FORCEPROP 1 LAST PATH I164
J 2
(-2848 4350);
DISPLAY 0.872340 (-2848 4350);
PAINT GREEN (-2848 4350);
DISPLAY INVISIBLE (-2848 4350);
FORCEADD TAP..6
R 2
(-2850 4500);
FORCEPROP 3 LASTPIN (-2900 4500) SIG_NAME M_J_DQS_DP<14>
J 0
(-2890 4510);
DISPLAY 0.659574 (-2890 4510);
PAINT MONO (-2890 4510);
DISPLAY INVISIBLE (-2890 4510);
FORCEPROP 1 LASTPIN (-2900 4500) BN 14
J 2
(-2848 4508);
DISPLAY 0.617021 (-2848 4508);
PAINT GREEN (-2848 4508);
FORCEPROP 2 LAST CDS_LIB mstr_standard
J 0
(-2850 4500);
PAINT MONO (-2850 4500);
DISPLAY INVISIBLE (-2850 4500);
FORCEPROP 1 LAST BODY_TYPE PLUMBING
J 2
(-2850 4450);
DISPLAY 1.595745 (-2850 4450);
PAINT GREEN (-2850 4450);
DISPLAY INVISIBLE (-2850 4450);
FORCEPROP 1 LAST HDL_TAP TRUE
J 2
(-3175 4375);
DISPLAY 1.595745 (-3175 4375);
PAINT GREEN (-3175 4375);
DISPLAY INVISIBLE (-3175 4375);
FORCEPROP 1 LAST PATH I165
J 2
(-2848 4500);
DISPLAY 0.872340 (-2848 4500);
PAINT GREEN (-2848 4500);
DISPLAY INVISIBLE (-2848 4500);
FORCEADD TAP..6
R 2
(-2850 4450);
FORCEPROP 3 LASTPIN (-2900 4450) SIG_NAME M_J_DQS_DP<13>
J 0
(-2890 4460);
DISPLAY 0.659574 (-2890 4460);
PAINT MONO (-2890 4460);
DISPLAY INVISIBLE (-2890 4460);
FORCEPROP 1 LASTPIN (-2900 4450) BN 13
J 2
(-2848 4458);
DISPLAY 0.617021 (-2848 4458);
PAINT GREEN (-2848 4458);
FORCEPROP 2 LAST CDS_LIB mstr_standard
J 0
(-2850 4450);
PAINT MONO (-2850 4450);
DISPLAY INVISIBLE (-2850 4450);
FORCEPROP 1 LAST BODY_TYPE PLUMBING
J 2
(-2850 4400);
DISPLAY 1.595745 (-2850 4400);
PAINT GREEN (-2850 4400);
DISPLAY INVISIBLE (-2850 4400);
FORCEPROP 1 LAST HDL_TAP TRUE
J 2
(-3175 4325);
DISPLAY 1.595745 (-3175 4325);
PAINT GREEN (-3175 4325);
DISPLAY INVISIBLE (-3175 4325);
FORCEPROP 1 LAST PATH I166
J 2
(-2848 4450);
DISPLAY 0.872340 (-2848 4450);
PAINT GREEN (-2848 4450);
DISPLAY INVISIBLE (-2848 4450);
FORCEADD TAP..6
R 2
(-2850 4400);
FORCEPROP 3 LASTPIN (-2900 4400) SIG_NAME M_J_DQS_DP<12>
J 0
(-2890 4410);
DISPLAY 0.659574 (-2890 4410);
PAINT MONO (-2890 4410);
DISPLAY INVISIBLE (-2890 4410);
FORCEPROP 1 LASTPIN (-2900 4400) BN 12
J 2
(-2848 4408);
DISPLAY 0.617021 (-2848 4408);
PAINT GREEN (-2848 4408);
FORCEPROP 2 LAST CDS_LIB mstr_standard
J 0
(-2850 4400);
PAINT MONO (-2850 4400);
DISPLAY INVISIBLE (-2850 4400);
FORCEPROP 1 LAST BODY_TYPE PLUMBING
J 2
(-2850 4350);
DISPLAY 1.595745 (-2850 4350);
PAINT GREEN (-2850 4350);
DISPLAY INVISIBLE (-2850 4350);
FORCEPROP 1 LAST HDL_TAP TRUE
J 2
(-3175 4275);
DISPLAY 1.595745 (-3175 4275);
PAINT GREEN (-3175 4275);
DISPLAY INVISIBLE (-3175 4275);
FORCEPROP 1 LAST PATH I167
J 2
(-2848 4400);
DISPLAY 0.872340 (-2848 4400);
PAINT GREEN (-2848 4400);
DISPLAY INVISIBLE (-2848 4400);
FORCEADD TAP..6
R 2
(-2850 4550);
FORCEPROP 3 LASTPIN (-2900 4550) SIG_NAME M_J_DQS_DP<15>
J 0
(-2890 4560);
DISPLAY 0.659574 (-2890 4560);
PAINT MONO (-2890 4560);
DISPLAY INVISIBLE (-2890 4560);
FORCEPROP 1 LASTPIN (-2900 4550) BN 15
J 2
(-2848 4558);
DISPLAY 0.617021 (-2848 4558);
PAINT GREEN (-2848 4558);
FORCEPROP 2 LAST CDS_LIB mstr_standard
J 0
(-2850 4550);
PAINT MONO (-2850 4550);
DISPLAY INVISIBLE (-2850 4550);
FORCEPROP 1 LAST BODY_TYPE PLUMBING
J 2
(-2850 4500);
DISPLAY 1.595745 (-2850 4500);
PAINT GREEN (-2850 4500);
DISPLAY INVISIBLE (-2850 4500);
FORCEPROP 1 LAST HDL_TAP TRUE
J 2
(-3175 4425);
DISPLAY 1.595745 (-3175 4425);
PAINT GREEN (-3175 4425);
DISPLAY INVISIBLE (-3175 4425);
FORCEPROP 1 LAST PATH I168
J 2
(-2848 4550);
DISPLAY 0.872340 (-2848 4550);
PAINT GREEN (-2848 4550);
DISPLAY INVISIBLE (-2848 4550);
FORCEADD TAP..6
R 2
(-2850 4600);
FORCEPROP 3 LASTPIN (-2900 4600) SIG_NAME M_J_DQS_DP<16>
J 0
(-2890 4610);
DISPLAY 0.659574 (-2890 4610);
PAINT MONO (-2890 4610);
DISPLAY INVISIBLE (-2890 4610);
FORCEPROP 1 LASTPIN (-2900 4600) BN 16
J 2
(-2848 4608);
DISPLAY 0.617021 (-2848 4608);
PAINT GREEN (-2848 4608);
FORCEPROP 2 LAST CDS_LIB mstr_standard
J 0
(-2850 4600);
PAINT MONO (-2850 4600);
DISPLAY INVISIBLE (-2850 4600);
FORCEPROP 1 LAST BODY_TYPE PLUMBING
J 2
(-2850 4550);
DISPLAY 1.595745 (-2850 4550);
PAINT GREEN (-2850 4550);
DISPLAY INVISIBLE (-2850 4550);
FORCEPROP 1 LAST HDL_TAP TRUE
J 2
(-3175 4475);
DISPLAY 1.595745 (-3175 4475);
PAINT GREEN (-3175 4475);
DISPLAY INVISIBLE (-3175 4475);
FORCEPROP 1 LAST PATH I169
J 2
(-2848 4600);
DISPLAY 0.872340 (-2848 4600);
PAINT GREEN (-2848 4600);
DISPLAY INVISIBLE (-2848 4600);
FORCEADD TAP..6
(-5575 1200);
FORCEPROP 3 LASTPIN (-5525 1200) SIG_NAME M_J_ECC<3>
J 0
(-5515 1210);
DISPLAY 0.659574 (-5515 1210);
PAINT MONO (-5515 1210);
DISPLAY INVISIBLE (-5515 1210);
FORCEPROP 1 LASTPIN (-5525 1200) BN 3
J 0
(-5577 1208);
DISPLAY 0.617021 (-5577 1208);
PAINT GREEN (-5577 1208);
FORCEPROP 2 LAST CDS_LIB mstr_standard
J 0
(-5575 1200);
PAINT MONO (-5575 1200);
DISPLAY INVISIBLE (-5575 1200);
FORCEPROP 1 LAST BODY_TYPE PLUMBING
J 0
(-5575 1150);
DISPLAY 1.595745 (-5575 1150);
PAINT GREEN (-5575 1150);
DISPLAY INVISIBLE (-5575 1150);
FORCEPROP 1 LAST HDL_TAP TRUE
J 0
(-5250 1075);
DISPLAY 1.595745 (-5250 1075);
PAINT GREEN (-5250 1075);
DISPLAY INVISIBLE (-5250 1075);
FORCEPROP 1 LAST PATH I17
J 0
(-5577 1200);
DISPLAY 0.872340 (-5577 1200);
PAINT GREEN (-5577 1200);
DISPLAY INVISIBLE (-5577 1200);
FORCEADD TAP..6
R 2
(-2850 4650);
FORCEPROP 3 LASTPIN (-2900 4650) SIG_NAME M_J_DQS_DP<17>
J 0
(-2890 4660);
DISPLAY 0.659574 (-2890 4660);
PAINT MONO (-2890 4660);
DISPLAY INVISIBLE (-2890 4660);
FORCEPROP 1 LASTPIN (-2900 4650) BN 17
J 2
(-2848 4658);
DISPLAY 0.617021 (-2848 4658);
PAINT GREEN (-2848 4658);
FORCEPROP 2 LAST CDS_LIB mstr_standard
J 2
(-2850 4650);
PAINT MONO (-2850 4650);
DISPLAY INVISIBLE (-2850 4650);
FORCEPROP 1 LAST BODY_TYPE PLUMBING
J 2
(-2850 4600);
DISPLAY 1.595745 (-2850 4600);
PAINT GREEN (-2850 4600);
DISPLAY INVISIBLE (-2850 4600);
FORCEPROP 1 LAST HDL_TAP TRUE
J 2
(-3175 4525);
DISPLAY 1.595745 (-3175 4525);
PAINT GREEN (-3175 4525);
DISPLAY INVISIBLE (-3175 4525);
FORCEPROP 1 LAST PATH I170
J 2
(-2848 4650);
DISPLAY 0.872340 (-2848 4650);
PAINT GREEN (-2848 4650);
DISPLAY INVISIBLE (-2848 4650);
FORCEADD OFFPAGE..3
(-2000 4725);
FORCEPROP 2 LAST $XR0 81 
J 0
(-1786 4725);
DISPLAY 0.638298 (-1786 4725);
PAINT MONO (-1786 4725);
FORCEPROP 2 LAST $XR1 82 
J 0
(-1696 4725);
DISPLAY 0.638298 (-1696 4725);
PAINT MONO (-1696 4725);
FORCEPROP 2 LAST CDS_LIB mstr_standard
J 0
(-2000 4725);
PAINT MONO (-2000 4725);
DISPLAY INVISIBLE (-2000 4725);
FORCEPROP 1 LAST OFFPAGE TRUE
J 0
(-1675 4600);
DISPLAY 1.170213 (-1675 4600);
PAINT GREEN (-1675 4600);
DISPLAY INVISIBLE (-1675 4600);
FORCEPROP 1 LAST COMMENT_BODY TRUE
J 0
(-2050 4625);
DISPLAY 1.170213 (-2050 4625);
PAINT GREEN (-2050 4625);
DISPLAY INVISIBLE (-2050 4625);
FORCEPROP 2 LAST PATH I171
J 0
(-1800 4800);
DISPLAY 1.021277 (-1800 4800);
PAINT ORANGE (-1800 4800);
DISPLAY INVISIBLE (-1800 4800);
FORCEADD SKX_EXT_B..5
(-4175 2550);
FORCEPROP 1 LAST LOCATION U2D1
J 0
(-4975 4900);
DISPLAY 0.617021 (-4975 4900);
PAINT AQUA (-4975 4900);
FORCEPROP 1 LAST PART_NUMBER TBD
J 0
(-4975 300);
DISPLAY 0.617021 (-4975 300);
PAINT BLUE (-4975 300);
FORCEPROP 1 LAST MATERIAL IC
J 0
(-4975 4850);
DISPLAY 0.617021 (-4975 4850);
PAINT SKYBLUE (-4975 4850);
FORCEPROP 2 LASTPIN (-3325 500) $PN V53
J 0
(-3315 510);
DISPLAY 0.617021 (-3315 510);
PAINT ORANGE (-3315 510);
FORCEPROP 2 LASTPIN (-3325 1550) $PN AB47
J 0
(-3315 1560);
DISPLAY 0.617021 (-3315 1560);
PAINT ORANGE (-3315 1560);
FORCEPROP 2 LASTPIN (-3325 1500) $PN V49
J 0
(-3315 1510);
DISPLAY 0.617021 (-3315 1510);
PAINT ORANGE (-3315 1510);
FORCEPROP 2 LASTPIN (-3325 1450) $PN AA48
J 0
(-3315 1460);
DISPLAY 0.617021 (-3315 1460);
PAINT ORANGE (-3315 1460);
FORCEPROP 2 LASTPIN (-3325 1400) $PN AA50
J 0
(-3315 1410);
DISPLAY 0.617021 (-3315 1410);
PAINT ORANGE (-3315 1410);
FORCEPROP 2 LASTPIN (-3325 2750) $PN AC46
J 0
(-3315 2760);
DISPLAY 0.617021 (-3315 2760);
PAINT ORANGE (-3315 2760);
FORCEPROP 2 LASTPIN (-3325 2700) $PN AA52
J 0
(-3315 2710);
DISPLAY 0.617021 (-3315 2710);
PAINT ORANGE (-3315 2710);
FORCEPROP 2 LASTPIN (-3325 2650) $PN AE54
J 0
(-3315 2660);
DISPLAY 0.617021 (-3315 2660);
PAINT ORANGE (-3315 2660);
FORCEPROP 2 LASTPIN (-3325 2600) $PN W50
J 0
(-3315 2610);
DISPLAY 0.617021 (-3315 2610);
PAINT ORANGE (-3315 2610);
FORCEPROP 2 LASTPIN (-3325 2550) $PN AD53
J 0
(-3315 2560);
DISPLAY 0.617021 (-3315 2560);
PAINT ORANGE (-3315 2560);
FORCEPROP 2 LASTPIN (-3325 2500) $PN AG62
J 0
(-3315 2510);
DISPLAY 0.617021 (-3315 2510);
PAINT ORANGE (-3315 2510);
FORCEPROP 2 LASTPIN (-3325 2450) $PN AG60
J 0
(-3315 2460);
DISPLAY 0.617021 (-3315 2460);
PAINT ORANGE (-3315 2460);
FORCEPROP 2 LASTPIN (-3325 2400) $PN AD55
J 0
(-3315 2410);
DISPLAY 0.617021 (-3315 2410);
PAINT ORANGE (-3315 2410);
FORCEPROP 2 LASTPIN (-3325 2350) $PN AG58
J 0
(-3315 2360);
DISPLAY 0.617021 (-3315 2360);
PAINT ORANGE (-3315 2360);
FORCEPROP 2 LASTPIN (-3325 2300) $PN AD59
J 0
(-3315 2310);
DISPLAY 0.617021 (-3315 2310);
PAINT ORANGE (-3315 2310);
FORCEPROP 2 LASTPIN (-3325 2250) $PN AE60
J 0
(-3315 2260);
DISPLAY 0.617021 (-3315 2260);
PAINT ORANGE (-3315 2260);
FORCEPROP 2 LASTPIN (-3325 2200) $PN AB59
J 0
(-3315 2210);
DISPLAY 0.617021 (-3315 2210);
PAINT ORANGE (-3315 2210);
FORCEPROP 2 LASTPIN (-3325 2150) $PN V59
J 0
(-3315 2160);
DISPLAY 0.617021 (-3315 2160);
PAINT ORANGE (-3315 2160);
FORCEPROP 2 LASTPIN (-3325 2100) $PN AA58
J 0
(-3315 2110);
DISPLAY 0.617021 (-3315 2110);
PAINT ORANGE (-3315 2110);
FORCEPROP 2 LASTPIN (-3325 2050) $PN W58
J 0
(-3315 2060);
DISPLAY 0.617021 (-3315 2060);
PAINT ORANGE (-3315 2060);
FORCEPROP 2 LASTPIN (-3325 2000) $PN AD57
J 0
(-3315 2010);
DISPLAY 0.617021 (-3315 2010);
PAINT ORANGE (-3315 2010);
FORCEPROP 2 LASTPIN (-3325 1950) $PN AE58
J 0
(-3315 1960);
DISPLAY 0.617021 (-3315 1960);
PAINT ORANGE (-3315 1960);
FORCEPROP 2 LASTPIN (-3325 1900) $PN AB53
J 0
(-3315 1910);
DISPLAY 0.617021 (-3315 1910);
PAINT ORANGE (-3315 1910);
FORCEPROP 2 LASTPIN (-5025 1400) $PN BA70
J 2
(-5035 1410);
DISPLAY 0.617021 (-5035 1410);
PAINT ORANGE (-5035 1410);
FORCEPROP 2 LASTPIN (-5025 1350) $PN AU70
J 2
(-5035 1360);
DISPLAY 0.617021 (-5035 1360);
PAINT ORANGE (-5035 1360);
FORCEPROP 2 LASTPIN (-5025 1300) $PN AY73
J 2
(-5035 1310);
DISPLAY 0.617021 (-5035 1310);
PAINT ORANGE (-5035 1310);
FORCEPROP 2 LASTPIN (-5025 1250) $PN AV73
J 2
(-5035 1260);
DISPLAY 0.617021 (-5035 1260);
PAINT ORANGE (-5035 1260);
FORCEPROP 2 LASTPIN (-5025 1200) $PN AY69
J 2
(-5035 1210);
DISPLAY 0.617021 (-5035 1210);
PAINT ORANGE (-5035 1210);
FORCEPROP 2 LASTPIN (-5025 1150) $PN AV69
J 2
(-5035 1160);
DISPLAY 0.617021 (-5035 1160);
PAINT ORANGE (-5035 1160);
FORCEPROP 2 LASTPIN (-5025 1100) $PN BA72
J 2
(-5035 1110);
DISPLAY 0.617021 (-5035 1110);
PAINT ORANGE (-5035 1110);
FORCEPROP 2 LASTPIN (-5025 1050) $PN AU72
J 2
(-5035 1060);
DISPLAY 0.617021 (-5035 1060);
PAINT ORANGE (-5035 1060);
FORCEPROP 2 LASTPIN (-3325 4650) $PN AV71
J 0
(-3315 4660);
DISPLAY 0.617021 (-3315 4660);
PAINT ORANGE (-3315 4660);
FORCEPROP 2 LASTPIN (-3325 4600) $PN AE24
J 0
(-3315 4610);
DISPLAY 0.617021 (-3315 4610);
PAINT ORANGE (-3315 4610);
FORCEPROP 2 LASTPIN (-3325 4550) $PN AE30
J 0
(-3315 4560);
DISPLAY 0.617021 (-3315 4560);
PAINT ORANGE (-3315 4560);
FORCEPROP 2 LASTPIN (-3325 4500) $PN V33
J 0
(-3315 4510);
DISPLAY 0.617021 (-3315 4510);
PAINT ORANGE (-3315 4510);
FORCEPROP 2 LASTPIN (-3325 4450) $PN V39
J 0
(-3315 4460);
DISPLAY 0.617021 (-3315 4460);
PAINT ORANGE (-3315 4460);
FORCEPROP 2 LASTPIN (-3325 4400) $PN AN66
J 0
(-3315 4410);
DISPLAY 0.617021 (-3315 4410);
PAINT ORANGE (-3315 4410);
FORCEPROP 2 LASTPIN (-3325 4350) $PN V71
J 0
(-3315 4360);
DISPLAY 0.617021 (-3315 4360);
PAINT ORANGE (-3315 4360);
FORCEPROP 2 LASTPIN (-3325 4300) $PN AC76
J 0
(-3315 4310);
DISPLAY 0.617021 (-3315 4310);
PAINT ORANGE (-3315 4310);
FORCEPROP 2 LASTPIN (-3325 4250) $PN AN76
J 0
(-3315 4260);
DISPLAY 0.617021 (-3315 4260);
PAINT ORANGE (-3315 4260);
FORCEPROP 2 LASTPIN (-3325 4200) $PN AY71
J 0
(-3315 4210);
DISPLAY 0.617021 (-3315 4210);
PAINT ORANGE (-3315 4210);
FORCEPROP 2 LASTPIN (-3325 4150) $PN AG24
J 0
(-3315 4160);
DISPLAY 0.617021 (-3315 4160);
PAINT ORANGE (-3315 4160);
FORCEPROP 2 LASTPIN (-3325 4100) $PN AG30
J 0
(-3315 4110);
DISPLAY 0.617021 (-3315 4110);
PAINT ORANGE (-3315 4110);
FORCEPROP 2 LASTPIN (-3325 4050) $PN Y33
J 0
(-3315 4060);
DISPLAY 0.617021 (-3315 4060);
PAINT ORANGE (-3315 4060);
FORCEPROP 2 LASTPIN (-3325 4000) $PN Y39
J 0
(-3315 4010);
DISPLAY 0.617021 (-3315 4010);
PAINT ORANGE (-3315 4010);
FORCEPROP 2 LASTPIN (-3325 3950) $PN AR66
J 0
(-3315 3960);
DISPLAY 0.617021 (-3315 3960);
PAINT ORANGE (-3315 3960);
FORCEPROP 2 LASTPIN (-3325 3900) $PN W70
J 0
(-3315 3910);
DISPLAY 0.617021 (-3315 3910);
PAINT ORANGE (-3315 3910);
FORCEPROP 2 LASTPIN (-3325 3850) $PN AB75
J 0
(-3315 3860);
DISPLAY 0.617021 (-3315 3860);
PAINT ORANGE (-3315 3860);
FORCEPROP 2 LASTPIN (-3325 3800) $PN AM75
J 0
(-3315 3810);
DISPLAY 0.617021 (-3315 3810);
PAINT ORANGE (-3315 3810);
FORCEPROP 2 LASTPIN (-3325 3700) $PN AT71
J 0
(-3315 3710);
DISPLAY 0.617021 (-3315 3710);
PAINT ORANGE (-3315 3710);
FORCEPROP 2 LASTPIN (-3325 3650) $PN AC24
J 0
(-3315 3660);
DISPLAY 0.617021 (-3315 3660);
PAINT ORANGE (-3315 3660);
FORCEPROP 2 LASTPIN (-3325 3600) $PN AC30
J 0
(-3315 3610);
DISPLAY 0.617021 (-3315 3610);
PAINT ORANGE (-3315 3610);
FORCEPROP 2 LASTPIN (-3325 3550) $PN T33
J 0
(-3315 3560);
DISPLAY 0.617021 (-3315 3560);
PAINT ORANGE (-3315 3560);
FORCEPROP 2 LASTPIN (-3325 3500) $PN T39
J 0
(-3315 3510);
DISPLAY 0.617021 (-3315 3510);
PAINT ORANGE (-3315 3510);
FORCEPROP 2 LASTPIN (-3325 3450) $PN AL66
J 0
(-3315 3460);
DISPLAY 0.617021 (-3315 3460);
PAINT ORANGE (-3315 3460);
FORCEPROP 2 LASTPIN (-3325 3400) $PN U72
J 0
(-3315 3410);
DISPLAY 0.617021 (-3315 3410);
PAINT ORANGE (-3315 3410);
FORCEPROP 2 LASTPIN (-3325 3350) $PN AD77
J 0
(-3315 3360);
DISPLAY 0.617021 (-3315 3360);
PAINT ORANGE (-3315 3360);
FORCEPROP 2 LASTPIN (-3325 3300) $PN AP77
J 0
(-3315 3310);
DISPLAY 0.617021 (-3315 3310);
PAINT ORANGE (-3315 3310);
FORCEPROP 2 LASTPIN (-3325 3250) $PN BB71
J 0
(-3315 3260);
DISPLAY 0.617021 (-3315 3260);
PAINT ORANGE (-3315 3260);
FORCEPROP 2 LASTPIN (-3325 3200) $PN AJ24
J 0
(-3315 3210);
DISPLAY 0.617021 (-3315 3210);
PAINT ORANGE (-3315 3210);
FORCEPROP 2 LASTPIN (-3325 3150) $PN AJ30
J 0
(-3315 3160);
DISPLAY 0.617021 (-3315 3160);
PAINT ORANGE (-3315 3160);
FORCEPROP 2 LASTPIN (-3325 3100) $PN AB33
J 0
(-3315 3110);
DISPLAY 0.617021 (-3315 3110);
PAINT ORANGE (-3315 3110);
FORCEPROP 2 LASTPIN (-3325 3050) $PN AB39
J 0
(-3315 3060);
DISPLAY 0.617021 (-3315 3060);
PAINT ORANGE (-3315 3060);
FORCEPROP 2 LASTPIN (-3325 3000) $PN AU66
J 0
(-3315 3010);
DISPLAY 0.617021 (-3315 3010);
PAINT ORANGE (-3315 3010);
FORCEPROP 2 LASTPIN (-3325 2950) $PN Y69
J 0
(-3315 2960);
DISPLAY 0.617021 (-3315 2960);
PAINT ORANGE (-3315 2960);
FORCEPROP 2 LASTPIN (-3325 2900) $PN AA74
J 0
(-3315 2910);
DISPLAY 0.617021 (-3315 2910);
PAINT ORANGE (-3315 2910);
FORCEPROP 2 LASTPIN (-3325 2850) $PN AL74
J 0
(-3315 2860);
DISPLAY 0.617021 (-3315 2860);
PAINT ORANGE (-3315 2860);
FORCEPROP 2 LASTPIN (-5025 4650) $PN AH23
J 2
(-5035 4660);
DISPLAY 0.617021 (-5035 4660);
PAINT ORANGE (-5035 4660);
FORCEPROP 2 LASTPIN (-5025 4600) $PN AD23
J 2
(-5035 4610);
DISPLAY 0.617021 (-5035 4610);
PAINT ORANGE (-5035 4610);
FORCEPROP 2 LASTPIN (-5025 4550) $PN AG26
J 2
(-5035 4560);
DISPLAY 0.617021 (-5035 4560);
PAINT ORANGE (-5035 4560);
FORCEPROP 2 LASTPIN (-5025 4500) $PN AE26
J 2
(-5035 4510);
DISPLAY 0.617021 (-5035 4510);
PAINT ORANGE (-5035 4510);
FORCEPROP 2 LASTPIN (-5025 4450) $PN AG22
J 2
(-5035 4460);
DISPLAY 0.617021 (-5035 4460);
PAINT ORANGE (-5035 4460);
FORCEPROP 2 LASTPIN (-5025 4400) $PN AE22
J 2
(-5035 4410);
DISPLAY 0.617021 (-5035 4410);
PAINT ORANGE (-5035 4410);
FORCEPROP 2 LASTPIN (-5025 4350) $PN AH25
J 2
(-5035 4360);
DISPLAY 0.617021 (-5035 4360);
PAINT ORANGE (-5035 4360);
FORCEPROP 2 LASTPIN (-5025 4300) $PN AD25
J 2
(-5035 4310);
DISPLAY 0.617021 (-5035 4310);
PAINT ORANGE (-5035 4310);
FORCEPROP 2 LASTPIN (-5025 4250) $PN AH29
J 2
(-5035 4260);
DISPLAY 0.617021 (-5035 4260);
PAINT ORANGE (-5035 4260);
FORCEPROP 2 LASTPIN (-5025 4200) $PN AD29
J 2
(-5035 4210);
DISPLAY 0.617021 (-5035 4210);
PAINT ORANGE (-5035 4210);
FORCEPROP 2 LASTPIN (-5025 4150) $PN AG32
J 2
(-5035 4160);
DISPLAY 0.617021 (-5035 4160);
PAINT ORANGE (-5035 4160);
FORCEPROP 2 LASTPIN (-5025 4100) $PN AE32
J 2
(-5035 4110);
DISPLAY 0.617021 (-5035 4110);
PAINT ORANGE (-5035 4110);
FORCEPROP 2 LASTPIN (-5025 4050) $PN AG28
J 2
(-5035 4060);
DISPLAY 0.617021 (-5035 4060);
PAINT ORANGE (-5035 4060);
FORCEPROP 2 LASTPIN (-5025 4000) $PN AE28
J 2
(-5035 4010);
DISPLAY 0.617021 (-5035 4010);
PAINT ORANGE (-5035 4010);
FORCEPROP 2 LASTPIN (-5025 3950) $PN AH31
J 2
(-5035 3960);
DISPLAY 0.617021 (-5035 3960);
PAINT ORANGE (-5035 3960);
FORCEPROP 2 LASTPIN (-5025 3900) $PN AD31
J 2
(-5035 3910);
DISPLAY 0.617021 (-5035 3910);
PAINT ORANGE (-5035 3910);
FORCEPROP 2 LASTPIN (-5025 3850) $PN AA32
J 2
(-5035 3860);
DISPLAY 0.617021 (-5035 3860);
PAINT ORANGE (-5035 3860);
FORCEPROP 2 LASTPIN (-5025 3800) $PN U32
J 2
(-5035 3810);
DISPLAY 0.617021 (-5035 3810);
PAINT ORANGE (-5035 3810);
FORCEPROP 2 LASTPIN (-5025 3750) $PN Y35
J 2
(-5035 3760);
DISPLAY 0.617021 (-5035 3760);
PAINT ORANGE (-5035 3760);
FORCEPROP 2 LASTPIN (-5025 3700) $PN V35
J 2
(-5035 3710);
DISPLAY 0.617021 (-5035 3710);
PAINT ORANGE (-5035 3710);
FORCEPROP 2 LASTPIN (-5025 3650) $PN Y31
J 2
(-5035 3660);
DISPLAY 0.617021 (-5035 3660);
PAINT ORANGE (-5035 3660);
FORCEPROP 2 LASTPIN (-5025 3600) $PN V31
J 2
(-5035 3610);
DISPLAY 0.617021 (-5035 3610);
PAINT ORANGE (-5035 3610);
FORCEPROP 2 LASTPIN (-5025 3550) $PN AA34
J 2
(-5035 3560);
DISPLAY 0.617021 (-5035 3560);
PAINT ORANGE (-5035 3560);
FORCEPROP 2 LASTPIN (-5025 3500) $PN U34
J 2
(-5035 3510);
DISPLAY 0.617021 (-5035 3510);
PAINT ORANGE (-5035 3510);
FORCEPROP 2 LASTPIN (-5025 3450) $PN AA38
J 2
(-5035 3460);
DISPLAY 0.617021 (-5035 3460);
PAINT ORANGE (-5035 3460);
FORCEPROP 2 LASTPIN (-5025 3400) $PN U38
J 2
(-5035 3410);
DISPLAY 0.617021 (-5035 3410);
PAINT ORANGE (-5035 3410);
FORCEPROP 2 LASTPIN (-5025 3350) $PN Y41
J 2
(-5035 3360);
DISPLAY 0.617021 (-5035 3360);
PAINT ORANGE (-5035 3360);
FORCEPROP 2 LASTPIN (-5025 3300) $PN V41
J 2
(-5035 3310);
DISPLAY 0.617021 (-5035 3310);
PAINT ORANGE (-5035 3310);
FORCEPROP 2 LASTPIN (-5025 3250) $PN Y37
J 2
(-5035 3260);
DISPLAY 0.617021 (-5035 3260);
PAINT ORANGE (-5035 3260);
FORCEPROP 2 LASTPIN (-5025 3200) $PN V37
J 2
(-5035 3210);
DISPLAY 0.617021 (-5035 3210);
PAINT ORANGE (-5035 3210);
FORCEPROP 2 LASTPIN (-5025 3150) $PN AA40
J 2
(-5035 3160);
DISPLAY 0.617021 (-5035 3160);
PAINT ORANGE (-5035 3160);
FORCEPROP 2 LASTPIN (-5025 3100) $PN U40
J 2
(-5035 3110);
DISPLAY 0.617021 (-5035 3110);
PAINT ORANGE (-5035 3110);
FORCEPROP 2 LASTPIN (-5025 3050) $PN AT65
J 2
(-5035 3060);
DISPLAY 0.617021 (-5035 3060);
PAINT ORANGE (-5035 3060);
FORCEPROP 2 LASTPIN (-5025 3000) $PN AM65
J 2
(-5035 3010);
DISPLAY 0.617021 (-5035 3010);
PAINT ORANGE (-5035 3010);
FORCEPROP 2 LASTPIN (-5025 2950) $PN AR68
J 2
(-5035 2960);
DISPLAY 0.617021 (-5035 2960);
PAINT ORANGE (-5035 2960);
FORCEPROP 2 LASTPIN (-5025 2900) $PN AN68
J 2
(-5035 2910);
DISPLAY 0.617021 (-5035 2910);
PAINT ORANGE (-5035 2910);
FORCEPROP 2 LASTPIN (-5025 2850) $PN AR64
J 2
(-5035 2860);
DISPLAY 0.617021 (-5035 2860);
PAINT ORANGE (-5035 2860);
FORCEPROP 2 LASTPIN (-5025 2800) $PN AN64
J 2
(-5035 2810);
DISPLAY 0.617021 (-5035 2810);
PAINT ORANGE (-5035 2810);
FORCEPROP 2 LASTPIN (-5025 2750) $PN AT67
J 2
(-5035 2760);
DISPLAY 0.617021 (-5035 2760);
PAINT ORANGE (-5035 2760);
FORCEPROP 2 LASTPIN (-5025 2700) $PN AM67
J 2
(-5035 2710);
DISPLAY 0.617021 (-5035 2710);
PAINT ORANGE (-5035 2710);
FORCEPROP 2 LASTPIN (-5025 2650) $PN V69
J 2
(-5035 2660);
DISPLAY 0.617021 (-5035 2660);
PAINT ORANGE (-5035 2660);
FORCEPROP 2 LASTPIN (-5025 2600) $PN T71
J 2
(-5035 2610);
DISPLAY 0.617021 (-5035 2610);
PAINT ORANGE (-5035 2610);
FORCEPROP 2 LASTPIN (-5025 2550) $PN AB71
J 2
(-5035 2560);
DISPLAY 0.617021 (-5035 2560);
PAINT ORANGE (-5035 2560);
FORCEPROP 2 LASTPIN (-5025 2500) $PN AA72
J 2
(-5035 2510);
DISPLAY 0.617021 (-5035 2510);
PAINT ORANGE (-5035 2510);
FORCEPROP 2 LASTPIN (-5025 2450) $PN T69
J 2
(-5035 2460);
DISPLAY 0.617021 (-5035 2460);
PAINT ORANGE (-5035 2460);
FORCEPROP 2 LASTPIN (-5025 2400) $PN R70
J 2
(-5035 2410);
DISPLAY 0.617021 (-5035 2410);
PAINT ORANGE (-5035 2410);
FORCEPROP 2 LASTPIN (-5025 2350) $PN AA70
J 2
(-5035 2360);
DISPLAY 0.617021 (-5035 2360);
PAINT ORANGE (-5035 2360);
FORCEPROP 2 LASTPIN (-5025 2300) $PN W72
J 2
(-5035 2310);
DISPLAY 0.617021 (-5035 2310);
PAINT ORANGE (-5035 2310);
FORCEPROP 2 LASTPIN (-5025 2250) $PN Y75
J 2
(-5035 2260);
DISPLAY 0.617021 (-5035 2260);
PAINT ORANGE (-5035 2260);
FORCEPROP 2 LASTPIN (-5025 2200) $PN AB77
J 2
(-5035 2210);
DISPLAY 0.617021 (-5035 2210);
PAINT ORANGE (-5035 2210);
FORCEPROP 2 LASTPIN (-5025 2150) $PN AE74
J 2
(-5035 2160);
DISPLAY 0.617021 (-5035 2160);
PAINT ORANGE (-5035 2160);
FORCEPROP 2 LASTPIN (-5025 2100) $PN AF75
J 2
(-5035 2110);
DISPLAY 0.617021 (-5035 2110);
PAINT ORANGE (-5035 2110);
FORCEPROP 2 LASTPIN (-5025 2050) $PN W76
J 2
(-5035 2060);
DISPLAY 0.617021 (-5035 2060);
PAINT ORANGE (-5035 2060);
FORCEPROP 2 LASTPIN (-5025 2000) $PN Y77
J 2
(-5035 2010);
DISPLAY 0.617021 (-5035 2010);
PAINT ORANGE (-5035 2010);
FORCEPROP 2 LASTPIN (-5025 1950) $PN AC74
J 2
(-5035 1960);
DISPLAY 0.617021 (-5035 1960);
PAINT ORANGE (-5035 1960);
FORCEPROP 2 LASTPIN (-5025 1900) $PN AE76
J 2
(-5035 1910);
DISPLAY 0.617021 (-5035 1910);
PAINT ORANGE (-5035 1910);
FORCEPROP 2 LASTPIN (-5025 1850) $PN AK75
J 2
(-5035 1860);
DISPLAY 0.617021 (-5035 1860);
PAINT ORANGE (-5035 1860);
FORCEPROP 2 LASTPIN (-5025 1800) $PN AM77
J 2
(-5035 1810);
DISPLAY 0.617021 (-5035 1810);
PAINT ORANGE (-5035 1810);
FORCEPROP 2 LASTPIN (-5025 1750) $PN AR74
J 2
(-5035 1760);
DISPLAY 0.617021 (-5035 1760);
PAINT ORANGE (-5035 1760);
FORCEPROP 2 LASTPIN (-5025 1700) $PN AT75
J 2
(-5035 1710);
DISPLAY 0.617021 (-5035 1710);
PAINT ORANGE (-5035 1710);
FORCEPROP 2 LASTPIN (-5025 1650) $PN AJ76
J 2
(-5035 1660);
DISPLAY 0.617021 (-5035 1660);
PAINT ORANGE (-5035 1660);
FORCEPROP 2 LASTPIN (-5025 1600) $PN AK77
J 2
(-5035 1610);
DISPLAY 0.617021 (-5035 1610);
PAINT ORANGE (-5035 1610);
FORCEPROP 2 LASTPIN (-5025 1550) $PN AN74
J 2
(-5035 1560);
DISPLAY 0.617021 (-5035 1560);
PAINT ORANGE (-5035 1560);
FORCEPROP 2 LASTPIN (-5025 1500) $PN AR76
J 2
(-5035 1510);
DISPLAY 0.617021 (-5035 1510);
PAINT ORANGE (-5035 1510);
FORCEPROP 2 LASTPIN (-3325 1300) $PN V45
J 0
(-3315 1310);
DISPLAY 0.617021 (-3315 1310);
PAINT ORANGE (-3315 1310);
FORCEPROP 2 LASTPIN (-3325 1250) $PN T45
J 0
(-3315 1260);
DISPLAY 0.617021 (-3315 1260);
PAINT ORANGE (-3315 1260);
FORCEPROP 2 LASTPIN (-3325 1200) $PN W48
J 0
(-3315 1210);
DISPLAY 0.617021 (-3315 1210);
PAINT ORANGE (-3315 1210);
FORCEPROP 2 LASTPIN (-3325 1150) $PN AB51
J 0
(-3315 1160);
DISPLAY 0.617021 (-3315 1160);
PAINT ORANGE (-3315 1160);
FORCEPROP 2 LASTPIN (-3325 1100) $PN AA46
J 0
(-3315 1110);
DISPLAY 0.617021 (-3315 1110);
PAINT ORANGE (-3315 1110);
FORCEPROP 2 LASTPIN (-3325 1050) $PN W46
J 0
(-3315 1060);
DISPLAY 0.617021 (-3315 1060);
PAINT ORANGE (-3315 1060);
FORCEPROP 2 LASTPIN (-3325 1000) $PN AB49
J 0
(-3315 1010);
DISPLAY 0.617021 (-3315 1010);
PAINT ORANGE (-3315 1010);
FORCEPROP 2 LASTPIN (-3325 950) $PN V51
J 0
(-3315 960);
DISPLAY 0.617021 (-3315 960);
PAINT ORANGE (-3315 960);
FORCEPROP 2 LASTPIN (-5025 950) $PN V57
J 2
(-5035 960);
DISPLAY 0.617021 (-5035 960);
PAINT ORANGE (-5035 960);
FORCEPROP 2 LASTPIN (-5025 900) $PN AB57
J 2
(-5035 910);
DISPLAY 0.617021 (-5035 910);
PAINT ORANGE (-5035 910);
FORCEPROP 2 LASTPIN (-5025 850) $PN V55
J 2
(-5035 860);
DISPLAY 0.617021 (-5035 860);
PAINT ORANGE (-5035 860);
FORCEPROP 2 LASTPIN (-5025 800) $PN AB55
J 2
(-5035 810);
DISPLAY 0.617021 (-5035 810);
PAINT ORANGE (-5035 810);
FORCEPROP 2 LASTPIN (-5025 750) $PN W56
J 2
(-5035 760);
DISPLAY 0.617021 (-5035 760);
PAINT ORANGE (-5035 760);
FORCEPROP 2 LASTPIN (-5025 700) $PN AA56
J 2
(-5035 710);
DISPLAY 0.617021 (-5035 710);
PAINT ORANGE (-5035 710);
FORCEPROP 2 LASTPIN (-5025 650) $PN W54
J 2
(-5035 660);
DISPLAY 0.617021 (-5035 660);
PAINT ORANGE (-5035 660);
FORCEPROP 2 LASTPIN (-5025 600) $PN AA54
J 2
(-5035 610);
DISPLAY 0.617021 (-5035 610);
PAINT ORANGE (-5035 610);
FORCEPROP 2 LASTPIN (-3325 1800) $PN AB63
J 0
(-3315 1810);
DISPLAY 0.617021 (-3315 1810);
PAINT ORANGE (-3315 1810);
FORCEPROP 2 LASTPIN (-3325 1750) $PN V63
J 0
(-3315 1760);
DISPLAY 0.617021 (-3315 1760);
PAINT ORANGE (-3315 1760);
FORCEPROP 2 LASTPIN (-3325 1700) $PN AD63
J 0
(-3315 1710);
DISPLAY 0.617021 (-3315 1710);
PAINT ORANGE (-3315 1710);
FORCEPROP 2 LASTPIN (-3325 1650) $PN AA62
J 0
(-3315 1660);
DISPLAY 0.617021 (-3315 1660);
PAINT ORANGE (-3315 1660);
FORCEPROP 2 LASTPIN (-5025 500) $PN AB45
J 2
(-5035 510);
DISPLAY 0.617021 (-5035 510);
PAINT ORANGE (-5035 510);
FORCEPROP 2 LASTPIN (-3325 850) $PN AE62
J 0
(-3315 860);
DISPLAY 0.617021 (-3315 860);
PAINT ORANGE (-3315 860);
FORCEPROP 2 LASTPIN (-3325 800) $PN AA60
J 0
(-3315 810);
DISPLAY 0.617021 (-3315 810);
PAINT ORANGE (-3315 810);
FORCEPROP 2 LASTPIN (-3325 750) $PN AE56
J 0
(-3315 760);
DISPLAY 0.617021 (-3315 760);
PAINT ORANGE (-3315 760);
FORCEPROP 2 LASTPIN (-3325 700) $PN W52
J 0
(-3315 710);
DISPLAY 0.617021 (-3315 710);
PAINT ORANGE (-3315 710);
FORCEPROP 2 LASTPIN (-3325 550) $PN AD61
J 0
(-3315 560);
DISPLAY 0.617021 (-3315 560);
PAINT ORANGE (-3315 560);
FORCEPROP 2 LASTPIN (-3325 600) $PN AB61
J 0
(-3315 610);
DISPLAY 0.617021 (-3315 610);
PAINT ORANGE (-3315 610);
FORCEPROP 1 LAST PACK_TYPE BGA1
J 0
(-4975 4950);
PAINT SKYBLUE (-4975 4950);
DISPLAY INVISIBLE (-4975 4950);
FORCEPROP 2 LAST SEC_TYPE BGA1
J 0
(-4975 4950);
DISPLAY 1.021277 (-4975 4950);
PAINT ORANGE (-4975 4950);
DISPLAY INVISIBLE (-4975 4950);
FORCEPROP 2 LAST CDS_LIB chpset_lib
J 0
(-4175 2550);
PAINT ORANGE (-4175 2550);
DISPLAY INVISIBLE (-4175 2550);
FORCEPROP 2 LAST SEC 5
J 0
(-4975 4950);
DISPLAY 0.680851 (-4975 4950);
PAINT MONO (-4975 4950);
DISPLAY INVISIBLE (-4975 4950);
FORCEPROP 2 LAST CDS_LOCATION U2D1
J 0
(-4975 4900);
DISPLAY 0.617021 (-4975 4900);
PAINT AQUA (-4975 4900);
DISPLAY INVISIBLE (-4975 4900);
FORCEPROP 1 LAST PATH I172
J 0
(-4175 4850);
PAINT GREEN (-4175 4850);
DISPLAY INVISIBLE (-4175 4850);
FORCEADD TAP..6
(-5575 1300);
FORCEPROP 3 LASTPIN (-5525 1300) SIG_NAME M_J_ECC<5>
J 0
(-5515 1310);
DISPLAY 0.659574 (-5515 1310);
PAINT MONO (-5515 1310);
DISPLAY INVISIBLE (-5515 1310);
FORCEPROP 1 LASTPIN (-5525 1300) BN 5
J 0
(-5577 1308);
DISPLAY 0.617021 (-5577 1308);
PAINT GREEN (-5577 1308);
FORCEPROP 2 LAST CDS_LIB mstr_standard
J 0
(-5575 1300);
PAINT MONO (-5575 1300);
DISPLAY INVISIBLE (-5575 1300);
FORCEPROP 1 LAST BODY_TYPE PLUMBING
J 0
(-5575 1250);
DISPLAY 1.595745 (-5575 1250);
PAINT GREEN (-5575 1250);
DISPLAY INVISIBLE (-5575 1250);
FORCEPROP 1 LAST HDL_TAP TRUE
J 0
(-5250 1175);
DISPLAY 1.595745 (-5250 1175);
PAINT GREEN (-5250 1175);
DISPLAY INVISIBLE (-5250 1175);
FORCEPROP 1 LAST PATH I18
J 0
(-5577 1300);
DISPLAY 0.872340 (-5577 1300);
PAINT GREEN (-5577 1300);
DISPLAY INVISIBLE (-5577 1300);
FORCEADD TAP..6
(-5575 1350);
FORCEPROP 3 LASTPIN (-5525 1350) SIG_NAME M_J_ECC<6>
J 0
(-5515 1360);
DISPLAY 0.659574 (-5515 1360);
PAINT MONO (-5515 1360);
DISPLAY INVISIBLE (-5515 1360);
FORCEPROP 1 LASTPIN (-5525 1350) BN 6
J 0
(-5577 1358);
DISPLAY 0.617021 (-5577 1358);
PAINT GREEN (-5577 1358);
FORCEPROP 2 LAST CDS_LIB mstr_standard
J 0
(-5575 1350);
PAINT MONO (-5575 1350);
DISPLAY INVISIBLE (-5575 1350);
FORCEPROP 1 LAST BODY_TYPE PLUMBING
J 0
(-5575 1300);
DISPLAY 1.595745 (-5575 1300);
PAINT GREEN (-5575 1300);
DISPLAY INVISIBLE (-5575 1300);
FORCEPROP 1 LAST HDL_TAP TRUE
J 0
(-5250 1225);
DISPLAY 1.595745 (-5250 1225);
PAINT GREEN (-5250 1225);
DISPLAY INVISIBLE (-5250 1225);
FORCEPROP 1 LAST PATH I19
J 0
(-5577 1350);
DISPLAY 0.872340 (-5577 1350);
PAINT GREEN (-5577 1350);
DISPLAY INVISIBLE (-5577 1350);
FORCEADD OFFPAGE..5
(-6425 800);
FORCEPROP 2 LAST $XR0 81 
J 0
(-6679 800);
DISPLAY 0.638298 (-6679 800);
PAINT MONO (-6679 800);
FORCEPROP 2 LAST $XR1 82 
J 0
(-6769 800);
DISPLAY 0.638298 (-6769 800);
PAINT MONO (-6769 800);
FORCEPROP 2 LAST CDS_LIB mstr_standard
J 0
(-6425 800);
PAINT MONO (-6425 800);
DISPLAY INVISIBLE (-6425 800);
FORCEPROP 1 LAST OFFPAGE TRUE
J 0
(-6100 675);
DISPLAY 1.170213 (-6100 675);
PAINT GREEN (-6100 675);
DISPLAY INVISIBLE (-6100 675);
FORCEPROP 1 LAST COMMENT_BODY TRUE
J 0
(-6325 725);
DISPLAY 1.170213 (-6325 725);
PAINT GREEN (-6325 725);
DISPLAY INVISIBLE (-6325 725);
FORCEPROP 2 LAST PATH I2
J 0
(-6375 875);
DISPLAY 1.021277 (-6375 875);
PAINT ORANGE (-6375 875);
DISPLAY INVISIBLE (-6375 875);
FORCEADD TAP..6
(-5575 1400);
FORCEPROP 3 LASTPIN (-5525 1400) SIG_NAME M_J_ECC<7>
J 0
(-5515 1410);
DISPLAY 0.659574 (-5515 1410);
PAINT MONO (-5515 1410);
DISPLAY INVISIBLE (-5515 1410);
FORCEPROP 1 LASTPIN (-5525 1400) BN 7
J 0
(-5577 1408);
DISPLAY 0.617021 (-5577 1408);
PAINT GREEN (-5577 1408);
FORCEPROP 2 LAST CDS_LIB mstr_standard
J 0
(-5575 1400);
PAINT MONO (-5575 1400);
DISPLAY INVISIBLE (-5575 1400);
FORCEPROP 1 LAST BODY_TYPE PLUMBING
J 0
(-5575 1350);
DISPLAY 1.595745 (-5575 1350);
PAINT GREEN (-5575 1350);
DISPLAY INVISIBLE (-5575 1350);
FORCEPROP 1 LAST HDL_TAP TRUE
J 0
(-5250 1275);
DISPLAY 1.595745 (-5250 1275);
PAINT GREEN (-5250 1275);
DISPLAY INVISIBLE (-5250 1275);
FORCEPROP 1 LAST PATH I20
J 0
(-5577 1400);
DISPLAY 0.872340 (-5577 1400);
PAINT GREEN (-5577 1400);
DISPLAY INVISIBLE (-5577 1400);
FORCEADD TAP..6
(-5575 1500);
FORCEPROP 3 LASTPIN (-5525 1500) SIG_NAME M_J_DQ<0>
J 0
(-5515 1510);
DISPLAY 0.659574 (-5515 1510);
PAINT MONO (-5515 1510);
DISPLAY INVISIBLE (-5515 1510);
FORCEPROP 1 LASTPIN (-5525 1500) BN 0
J 0
(-5577 1508);
DISPLAY 0.617021 (-5577 1508);
PAINT GREEN (-5577 1508);
FORCEPROP 2 LAST CDS_LIB mstr_standard
J 0
(-5575 1500);
PAINT MONO (-5575 1500);
DISPLAY INVISIBLE (-5575 1500);
FORCEPROP 1 LAST BODY_TYPE PLUMBING
J 0
(-5575 1450);
DISPLAY 1.595745 (-5575 1450);
PAINT GREEN (-5575 1450);
DISPLAY INVISIBLE (-5575 1450);
FORCEPROP 1 LAST HDL_TAP TRUE
J 0
(-5250 1375);
DISPLAY 1.595745 (-5250 1375);
PAINT GREEN (-5250 1375);
DISPLAY INVISIBLE (-5250 1375);
FORCEPROP 1 LAST PATH I21
J 0
(-5577 1500);
DISPLAY 0.872340 (-5577 1500);
PAINT GREEN (-5577 1500);
DISPLAY INVISIBLE (-5577 1500);
FORCEADD TAP..6
(-5575 1550);
FORCEPROP 3 LASTPIN (-5525 1550) SIG_NAME M_J_DQ<1>
J 0
(-5515 1560);
DISPLAY 0.659574 (-5515 1560);
PAINT MONO (-5515 1560);
DISPLAY INVISIBLE (-5515 1560);
FORCEPROP 1 LASTPIN (-5525 1550) BN 1
J 0
(-5577 1558);
DISPLAY 0.617021 (-5577 1558);
PAINT GREEN (-5577 1558);
FORCEPROP 2 LAST CDS_LIB mstr_standard
J 0
(-5575 1550);
PAINT MONO (-5575 1550);
DISPLAY INVISIBLE (-5575 1550);
FORCEPROP 1 LAST BODY_TYPE PLUMBING
J 0
(-5575 1500);
DISPLAY 1.595745 (-5575 1500);
PAINT GREEN (-5575 1500);
DISPLAY INVISIBLE (-5575 1500);
FORCEPROP 1 LAST HDL_TAP TRUE
J 0
(-5250 1425);
DISPLAY 1.595745 (-5250 1425);
PAINT GREEN (-5250 1425);
DISPLAY INVISIBLE (-5250 1425);
FORCEPROP 1 LAST PATH I22
J 0
(-5577 1550);
DISPLAY 0.872340 (-5577 1550);
PAINT GREEN (-5577 1550);
DISPLAY INVISIBLE (-5577 1550);
FORCEADD TAP..6
(-5575 1600);
FORCEPROP 3 LASTPIN (-5525 1600) SIG_NAME M_J_DQ<2>
J 0
(-5515 1610);
DISPLAY 0.659574 (-5515 1610);
PAINT MONO (-5515 1610);
DISPLAY INVISIBLE (-5515 1610);
FORCEPROP 1 LASTPIN (-5525 1600) BN 2
J 0
(-5577 1608);
DISPLAY 0.617021 (-5577 1608);
PAINT GREEN (-5577 1608);
FORCEPROP 2 LAST CDS_LIB mstr_standard
J 0
(-5575 1600);
PAINT MONO (-5575 1600);
DISPLAY INVISIBLE (-5575 1600);
FORCEPROP 1 LAST BODY_TYPE PLUMBING
J 0
(-5575 1550);
DISPLAY 1.595745 (-5575 1550);
PAINT GREEN (-5575 1550);
DISPLAY INVISIBLE (-5575 1550);
FORCEPROP 1 LAST HDL_TAP TRUE
J 0
(-5250 1475);
DISPLAY 1.595745 (-5250 1475);
PAINT GREEN (-5250 1475);
DISPLAY INVISIBLE (-5250 1475);
FORCEPROP 1 LAST PATH I23
J 0
(-5577 1600);
DISPLAY 0.872340 (-5577 1600);
PAINT GREEN (-5577 1600);
DISPLAY INVISIBLE (-5577 1600);
FORCEADD TAP..6
(-5575 1650);
FORCEPROP 3 LASTPIN (-5525 1650) SIG_NAME M_J_DQ<3>
J 0
(-5515 1660);
DISPLAY 0.659574 (-5515 1660);
PAINT MONO (-5515 1660);
DISPLAY INVISIBLE (-5515 1660);
FORCEPROP 1 LASTPIN (-5525 1650) BN 3
J 0
(-5577 1658);
DISPLAY 0.617021 (-5577 1658);
PAINT GREEN (-5577 1658);
FORCEPROP 2 LAST CDS_LIB mstr_standard
J 0
(-5575 1650);
PAINT MONO (-5575 1650);
DISPLAY INVISIBLE (-5575 1650);
FORCEPROP 1 LAST BODY_TYPE PLUMBING
J 0
(-5575 1600);
DISPLAY 1.595745 (-5575 1600);
PAINT GREEN (-5575 1600);
DISPLAY INVISIBLE (-5575 1600);
FORCEPROP 1 LAST HDL_TAP TRUE
J 0
(-5250 1525);
DISPLAY 1.595745 (-5250 1525);
PAINT GREEN (-5250 1525);
DISPLAY INVISIBLE (-5250 1525);
FORCEPROP 1 LAST PATH I24
J 0
(-5577 1650);
DISPLAY 0.872340 (-5577 1650);
PAINT GREEN (-5577 1650);
DISPLAY INVISIBLE (-5577 1650);
FORCEADD TAP..6
(-5575 1700);
FORCEPROP 3 LASTPIN (-5525 1700) SIG_NAME M_J_DQ<4>
J 0
(-5515 1710);
DISPLAY 0.659574 (-5515 1710);
PAINT MONO (-5515 1710);
DISPLAY INVISIBLE (-5515 1710);
FORCEPROP 1 LASTPIN (-5525 1700) BN 4
J 0
(-5577 1708);
DISPLAY 0.617021 (-5577 1708);
PAINT GREEN (-5577 1708);
FORCEPROP 2 LAST CDS_LIB mstr_standard
J 0
(-5575 1700);
PAINT MONO (-5575 1700);
DISPLAY INVISIBLE (-5575 1700);
FORCEPROP 1 LAST BODY_TYPE PLUMBING
J 0
(-5575 1650);
DISPLAY 1.595745 (-5575 1650);
PAINT GREEN (-5575 1650);
DISPLAY INVISIBLE (-5575 1650);
FORCEPROP 1 LAST HDL_TAP TRUE
J 0
(-5250 1575);
DISPLAY 1.595745 (-5250 1575);
PAINT GREEN (-5250 1575);
DISPLAY INVISIBLE (-5250 1575);
FORCEPROP 1 LAST PATH I25
J 0
(-5577 1700);
DISPLAY 0.872340 (-5577 1700);
PAINT GREEN (-5577 1700);
DISPLAY INVISIBLE (-5577 1700);
FORCEADD TAP..6
(-5575 1750);
FORCEPROP 3 LASTPIN (-5525 1750) SIG_NAME M_J_DQ<5>
J 0
(-5515 1760);
DISPLAY 0.659574 (-5515 1760);
PAINT MONO (-5515 1760);
DISPLAY INVISIBLE (-5515 1760);
FORCEPROP 1 LASTPIN (-5525 1750) BN 5
J 0
(-5577 1758);
DISPLAY 0.617021 (-5577 1758);
PAINT GREEN (-5577 1758);
FORCEPROP 2 LAST CDS_LIB mstr_standard
J 0
(-5575 1750);
PAINT MONO (-5575 1750);
DISPLAY INVISIBLE (-5575 1750);
FORCEPROP 1 LAST BODY_TYPE PLUMBING
J 0
(-5575 1700);
DISPLAY 1.595745 (-5575 1700);
PAINT GREEN (-5575 1700);
DISPLAY INVISIBLE (-5575 1700);
FORCEPROP 1 LAST HDL_TAP TRUE
J 0
(-5250 1625);
DISPLAY 1.595745 (-5250 1625);
PAINT GREEN (-5250 1625);
DISPLAY INVISIBLE (-5250 1625);
FORCEPROP 1 LAST PATH I26
J 0
(-5577 1750);
DISPLAY 0.872340 (-5577 1750);
PAINT GREEN (-5577 1750);
DISPLAY INVISIBLE (-5577 1750);
FORCEADD TAP..6
(-5575 1800);
FORCEPROP 3 LASTPIN (-5525 1800) SIG_NAME M_J_DQ<6>
J 0
(-5515 1810);
DISPLAY 0.659574 (-5515 1810);
PAINT MONO (-5515 1810);
DISPLAY INVISIBLE (-5515 1810);
FORCEPROP 1 LASTPIN (-5525 1800) BN 6
J 0
(-5577 1808);
DISPLAY 0.617021 (-5577 1808);
PAINT GREEN (-5577 1808);
FORCEPROP 2 LAST CDS_LIB mstr_standard
J 0
(-5575 1800);
PAINT MONO (-5575 1800);
DISPLAY INVISIBLE (-5575 1800);
FORCEPROP 1 LAST BODY_TYPE PLUMBING
J 0
(-5575 1750);
DISPLAY 1.595745 (-5575 1750);
PAINT GREEN (-5575 1750);
DISPLAY INVISIBLE (-5575 1750);
FORCEPROP 1 LAST HDL_TAP TRUE
J 0
(-5250 1675);
DISPLAY 1.595745 (-5250 1675);
PAINT GREEN (-5250 1675);
DISPLAY INVISIBLE (-5250 1675);
FORCEPROP 1 LAST PATH I27
J 0
(-5577 1800);
DISPLAY 0.872340 (-5577 1800);
PAINT GREEN (-5577 1800);
DISPLAY INVISIBLE (-5577 1800);
FORCEADD TAP..6
(-5575 1900);
FORCEPROP 3 LASTPIN (-5525 1900) SIG_NAME M_J_DQ<8>
J 0
(-5515 1910);
DISPLAY 0.659574 (-5515 1910);
PAINT MONO (-5515 1910);
DISPLAY INVISIBLE (-5515 1910);
FORCEPROP 1 LASTPIN (-5525 1900) BN 8
J 0
(-5577 1908);
DISPLAY 0.617021 (-5577 1908);
PAINT GREEN (-5577 1908);
FORCEPROP 2 LAST CDS_LIB mstr_standard
J 0
(-5575 1900);
PAINT MONO (-5575 1900);
DISPLAY INVISIBLE (-5575 1900);
FORCEPROP 1 LAST BODY_TYPE PLUMBING
J 0
(-5575 1850);
DISPLAY 1.595745 (-5575 1850);
PAINT GREEN (-5575 1850);
DISPLAY INVISIBLE (-5575 1850);
FORCEPROP 1 LAST HDL_TAP TRUE
J 0
(-5250 1775);
DISPLAY 1.595745 (-5250 1775);
PAINT GREEN (-5250 1775);
DISPLAY INVISIBLE (-5250 1775);
FORCEPROP 1 LAST PATH I28
J 0
(-5577 1900);
DISPLAY 0.872340 (-5577 1900);
PAINT GREEN (-5577 1900);
DISPLAY INVISIBLE (-5577 1900);
FORCEADD TAP..6
(-5575 1850);
FORCEPROP 3 LASTPIN (-5525 1850) SIG_NAME M_J_DQ<7>
J 0
(-5515 1860);
DISPLAY 0.659574 (-5515 1860);
PAINT MONO (-5515 1860);
DISPLAY INVISIBLE (-5515 1860);
FORCEPROP 1 LASTPIN (-5525 1850) BN 7
J 0
(-5577 1858);
DISPLAY 0.617021 (-5577 1858);
PAINT GREEN (-5577 1858);
FORCEPROP 2 LAST CDS_LIB mstr_standard
J 0
(-5575 1850);
PAINT MONO (-5575 1850);
DISPLAY INVISIBLE (-5575 1850);
FORCEPROP 1 LAST BODY_TYPE PLUMBING
J 0
(-5575 1800);
DISPLAY 1.595745 (-5575 1800);
PAINT GREEN (-5575 1800);
DISPLAY INVISIBLE (-5575 1800);
FORCEPROP 1 LAST HDL_TAP TRUE
J 0
(-5250 1725);
DISPLAY 1.595745 (-5250 1725);
PAINT GREEN (-5250 1725);
DISPLAY INVISIBLE (-5250 1725);
FORCEPROP 1 LAST PATH I29
J 0
(-5577 1850);
DISPLAY 0.872340 (-5577 1850);
PAINT GREEN (-5577 1850);
DISPLAY INVISIBLE (-5577 1850);
FORCEADD OFFPAGE..5
(-6425 1000);
FORCEPROP 2 LAST $XR0 81 
J 0
(-6679 1000);
DISPLAY 0.638298 (-6679 1000);
PAINT MONO (-6679 1000);
FORCEPROP 2 LAST $XR1 82 
J 0
(-6769 1000);
DISPLAY 0.638298 (-6769 1000);
PAINT MONO (-6769 1000);
FORCEPROP 2 LAST CDS_LIB mstr_standard
J 0
(-6425 1000);
PAINT MONO (-6425 1000);
DISPLAY INVISIBLE (-6425 1000);
FORCEPROP 1 LAST OFFPAGE TRUE
J 0
(-6100 875);
DISPLAY 1.170213 (-6100 875);
PAINT GREEN (-6100 875);
DISPLAY INVISIBLE (-6100 875);
FORCEPROP 1 LAST COMMENT_BODY TRUE
J 0
(-6325 925);
DISPLAY 1.170213 (-6325 925);
PAINT GREEN (-6325 925);
DISPLAY INVISIBLE (-6325 925);
FORCEPROP 2 LAST PATH I3
J 0
(-6375 1075);
DISPLAY 1.021277 (-6375 1075);
PAINT ORANGE (-6375 1075);
DISPLAY INVISIBLE (-6375 1075);
FORCEADD TAP..6
(-5575 1950);
FORCEPROP 3 LASTPIN (-5525 1950) SIG_NAME M_J_DQ<9>
J 0
(-5515 1960);
DISPLAY 0.659574 (-5515 1960);
PAINT MONO (-5515 1960);
DISPLAY INVISIBLE (-5515 1960);
FORCEPROP 1 LASTPIN (-5525 1950) BN 9
J 0
(-5577 1958);
DISPLAY 0.617021 (-5577 1958);
PAINT GREEN (-5577 1958);
FORCEPROP 2 LAST CDS_LIB mstr_standard
J 0
(-5575 1950);
PAINT MONO (-5575 1950);
DISPLAY INVISIBLE (-5575 1950);
FORCEPROP 1 LAST BODY_TYPE PLUMBING
J 0
(-5575 1900);
DISPLAY 1.595745 (-5575 1900);
PAINT GREEN (-5575 1900);
DISPLAY INVISIBLE (-5575 1900);
FORCEPROP 1 LAST HDL_TAP TRUE
J 0
(-5250 1825);
DISPLAY 1.595745 (-5250 1825);
PAINT GREEN (-5250 1825);
DISPLAY INVISIBLE (-5250 1825);
FORCEPROP 1 LAST PATH I31
J 0
(-5577 1950);
DISPLAY 0.872340 (-5577 1950);
PAINT GREEN (-5577 1950);
DISPLAY INVISIBLE (-5577 1950);
FORCEADD TAP..6
(-5575 2000);
FORCEPROP 3 LASTPIN (-5525 2000) SIG_NAME M_J_DQ<10>
J 0
(-5515 2010);
DISPLAY 0.659574 (-5515 2010);
PAINT MONO (-5515 2010);
DISPLAY INVISIBLE (-5515 2010);
FORCEPROP 1 LASTPIN (-5525 2000) BN 10
J 0
(-5577 2008);
DISPLAY 0.617021 (-5577 2008);
PAINT GREEN (-5577 2008);
FORCEPROP 2 LAST CDS_LIB mstr_standard
J 0
(-5575 2000);
PAINT MONO (-5575 2000);
DISPLAY INVISIBLE (-5575 2000);
FORCEPROP 1 LAST BODY_TYPE PLUMBING
J 0
(-5575 1950);
DISPLAY 1.595745 (-5575 1950);
PAINT GREEN (-5575 1950);
DISPLAY INVISIBLE (-5575 1950);
FORCEPROP 1 LAST HDL_TAP TRUE
J 0
(-5250 1875);
DISPLAY 1.595745 (-5250 1875);
PAINT GREEN (-5250 1875);
DISPLAY INVISIBLE (-5250 1875);
FORCEPROP 1 LAST PATH I32
J 0
(-5577 2000);
DISPLAY 0.872340 (-5577 2000);
PAINT GREEN (-5577 2000);
DISPLAY INVISIBLE (-5577 2000);
FORCEADD TAP..6
(-5575 2050);
FORCEPROP 3 LASTPIN (-5525 2050) SIG_NAME M_J_DQ<11>
J 0
(-5515 2060);
DISPLAY 0.659574 (-5515 2060);
PAINT MONO (-5515 2060);
DISPLAY INVISIBLE (-5515 2060);
FORCEPROP 1 LASTPIN (-5525 2050) BN 11
J 0
(-5577 2058);
DISPLAY 0.617021 (-5577 2058);
PAINT GREEN (-5577 2058);
FORCEPROP 2 LAST CDS_LIB mstr_standard
J 0
(-5575 2050);
PAINT MONO (-5575 2050);
DISPLAY INVISIBLE (-5575 2050);
FORCEPROP 1 LAST BODY_TYPE PLUMBING
J 0
(-5575 2000);
DISPLAY 1.595745 (-5575 2000);
PAINT GREEN (-5575 2000);
DISPLAY INVISIBLE (-5575 2000);
FORCEPROP 1 LAST HDL_TAP TRUE
J 0
(-5250 1925);
DISPLAY 1.595745 (-5250 1925);
PAINT GREEN (-5250 1925);
DISPLAY INVISIBLE (-5250 1925);
FORCEPROP 1 LAST PATH I33
J 0
(-5577 2050);
DISPLAY 0.872340 (-5577 2050);
PAINT GREEN (-5577 2050);
DISPLAY INVISIBLE (-5577 2050);
FORCEADD TAP..6
(-5575 2100);
FORCEPROP 3 LASTPIN (-5525 2100) SIG_NAME M_J_DQ<12>
J 0
(-5515 2110);
DISPLAY 0.659574 (-5515 2110);
PAINT MONO (-5515 2110);
DISPLAY INVISIBLE (-5515 2110);
FORCEPROP 1 LASTPIN (-5525 2100) BN 12
J 0
(-5577 2108);
DISPLAY 0.617021 (-5577 2108);
PAINT GREEN (-5577 2108);
FORCEPROP 2 LAST CDS_LIB mstr_standard
J 0
(-5575 2100);
PAINT MONO (-5575 2100);
DISPLAY INVISIBLE (-5575 2100);
FORCEPROP 1 LAST BODY_TYPE PLUMBING
J 0
(-5575 2050);
DISPLAY 1.595745 (-5575 2050);
PAINT GREEN (-5575 2050);
DISPLAY INVISIBLE (-5575 2050);
FORCEPROP 1 LAST HDL_TAP TRUE
J 0
(-5250 1975);
DISPLAY 1.595745 (-5250 1975);
PAINT GREEN (-5250 1975);
DISPLAY INVISIBLE (-5250 1975);
FORCEPROP 1 LAST PATH I34
J 0
(-5577 2100);
DISPLAY 0.872340 (-5577 2100);
PAINT GREEN (-5577 2100);
DISPLAY INVISIBLE (-5577 2100);
FORCEADD TAP..6
(-5575 2150);
FORCEPROP 3 LASTPIN (-5525 2150) SIG_NAME M_J_DQ<13>
J 0
(-5515 2160);
DISPLAY 0.659574 (-5515 2160);
PAINT MONO (-5515 2160);
DISPLAY INVISIBLE (-5515 2160);
FORCEPROP 1 LASTPIN (-5525 2150) BN 13
J 0
(-5577 2158);
DISPLAY 0.617021 (-5577 2158);
PAINT GREEN (-5577 2158);
FORCEPROP 2 LAST CDS_LIB mstr_standard
J 0
(-5575 2150);
PAINT MONO (-5575 2150);
DISPLAY INVISIBLE (-5575 2150);
FORCEPROP 1 LAST BODY_TYPE PLUMBING
J 0
(-5575 2100);
DISPLAY 1.595745 (-5575 2100);
PAINT GREEN (-5575 2100);
DISPLAY INVISIBLE (-5575 2100);
FORCEPROP 1 LAST HDL_TAP TRUE
J 0
(-5250 2025);
DISPLAY 1.595745 (-5250 2025);
PAINT GREEN (-5250 2025);
DISPLAY INVISIBLE (-5250 2025);
FORCEPROP 1 LAST PATH I35
J 0
(-5577 2150);
DISPLAY 0.872340 (-5577 2150);
PAINT GREEN (-5577 2150);
DISPLAY INVISIBLE (-5577 2150);
FORCEADD TAP..6
(-5575 2200);
FORCEPROP 3 LASTPIN (-5525 2200) SIG_NAME M_J_DQ<14>
J 0
(-5515 2210);
DISPLAY 0.659574 (-5515 2210);
PAINT MONO (-5515 2210);
DISPLAY INVISIBLE (-5515 2210);
FORCEPROP 1 LASTPIN (-5525 2200) BN 14
J 0
(-5577 2208);
DISPLAY 0.617021 (-5577 2208);
PAINT GREEN (-5577 2208);
FORCEPROP 2 LAST CDS_LIB mstr_standard
J 0
(-5575 2200);
PAINT MONO (-5575 2200);
DISPLAY INVISIBLE (-5575 2200);
FORCEPROP 1 LAST BODY_TYPE PLUMBING
J 0
(-5575 2150);
DISPLAY 1.595745 (-5575 2150);
PAINT GREEN (-5575 2150);
DISPLAY INVISIBLE (-5575 2150);
FORCEPROP 1 LAST HDL_TAP TRUE
J 0
(-5250 2075);
DISPLAY 1.595745 (-5250 2075);
PAINT GREEN (-5250 2075);
DISPLAY INVISIBLE (-5250 2075);
FORCEPROP 1 LAST PATH I36
J 0
(-5577 2200);
DISPLAY 0.872340 (-5577 2200);
PAINT GREEN (-5577 2200);
DISPLAY INVISIBLE (-5577 2200);
FORCEADD TAP..6
(-5575 2250);
FORCEPROP 3 LASTPIN (-5525 2250) SIG_NAME M_J_DQ<15>
J 0
(-5515 2260);
DISPLAY 0.659574 (-5515 2260);
PAINT MONO (-5515 2260);
DISPLAY INVISIBLE (-5515 2260);
FORCEPROP 1 LASTPIN (-5525 2250) BN 15
J 0
(-5577 2258);
DISPLAY 0.617021 (-5577 2258);
PAINT GREEN (-5577 2258);
FORCEPROP 2 LAST CDS_LIB mstr_standard
J 0
(-5575 2250);
PAINT MONO (-5575 2250);
DISPLAY INVISIBLE (-5575 2250);
FORCEPROP 1 LAST BODY_TYPE PLUMBING
J 0
(-5575 2200);
DISPLAY 1.595745 (-5575 2200);
PAINT GREEN (-5575 2200);
DISPLAY INVISIBLE (-5575 2200);
FORCEPROP 1 LAST HDL_TAP TRUE
J 0
(-5250 2125);
DISPLAY 1.595745 (-5250 2125);
PAINT GREEN (-5250 2125);
DISPLAY INVISIBLE (-5250 2125);
FORCEPROP 1 LAST PATH I37
J 0
(-5577 2250);
DISPLAY 0.872340 (-5577 2250);
PAINT GREEN (-5577 2250);
DISPLAY INVISIBLE (-5577 2250);
FORCEADD TAP..6
(-5575 2300);
FORCEPROP 3 LASTPIN (-5525 2300) SIG_NAME M_J_DQ<16>
J 0
(-5515 2310);
DISPLAY 0.659574 (-5515 2310);
PAINT MONO (-5515 2310);
DISPLAY INVISIBLE (-5515 2310);
FORCEPROP 1 LASTPIN (-5525 2300) BN 16
J 0
(-5577 2308);
DISPLAY 0.617021 (-5577 2308);
PAINT GREEN (-5577 2308);
FORCEPROP 2 LAST CDS_LIB mstr_standard
J 0
(-5575 2300);
PAINT MONO (-5575 2300);
DISPLAY INVISIBLE (-5575 2300);
FORCEPROP 1 LAST BODY_TYPE PLUMBING
J 0
(-5575 2250);
DISPLAY 1.595745 (-5575 2250);
PAINT GREEN (-5575 2250);
DISPLAY INVISIBLE (-5575 2250);
FORCEPROP 1 LAST HDL_TAP TRUE
J 0
(-5250 2175);
DISPLAY 1.595745 (-5250 2175);
PAINT GREEN (-5250 2175);
DISPLAY INVISIBLE (-5250 2175);
FORCEPROP 1 LAST PATH I38
J 0
(-5577 2300);
DISPLAY 0.872340 (-5577 2300);
PAINT GREEN (-5577 2300);
DISPLAY INVISIBLE (-5577 2300);
FORCEADD TAP..6
(-5575 2350);
FORCEPROP 3 LASTPIN (-5525 2350) SIG_NAME M_J_DQ<17>
J 0
(-5515 2360);
DISPLAY 0.659574 (-5515 2360);
PAINT MONO (-5515 2360);
DISPLAY INVISIBLE (-5515 2360);
FORCEPROP 1 LASTPIN (-5525 2350) BN 17
J 0
(-5577 2358);
DISPLAY 0.617021 (-5577 2358);
PAINT GREEN (-5577 2358);
FORCEPROP 2 LAST CDS_LIB mstr_standard
J 0
(-5575 2350);
PAINT MONO (-5575 2350);
DISPLAY INVISIBLE (-5575 2350);
FORCEPROP 1 LAST BODY_TYPE PLUMBING
J 0
(-5575 2300);
DISPLAY 1.595745 (-5575 2300);
PAINT GREEN (-5575 2300);
DISPLAY INVISIBLE (-5575 2300);
FORCEPROP 1 LAST HDL_TAP TRUE
J 0
(-5250 2225);
DISPLAY 1.595745 (-5250 2225);
PAINT GREEN (-5250 2225);
DISPLAY INVISIBLE (-5250 2225);
FORCEPROP 1 LAST PATH I39
J 0
(-5577 2350);
DISPLAY 0.872340 (-5577 2350);
PAINT GREEN (-5577 2350);
DISPLAY INVISIBLE (-5577 2350);
FORCEADD OFFPAGE..6
(-6425 1450);
FORCEPROP 2 LAST $XR0 81 
J 0
(-6674 1450);
DISPLAY 0.638298 (-6674 1450);
PAINT MONO (-6674 1450);
FORCEPROP 2 LAST $XR1 82 
J 0
(-6764 1450);
DISPLAY 0.638298 (-6764 1450);
PAINT MONO (-6764 1450);
FORCEPROP 2 LAST CDS_LIB mstr_standard
J 0
(-6425 1450);
PAINT MONO (-6425 1450);
DISPLAY INVISIBLE (-6425 1450);
FORCEPROP 1 LAST OFFPAGE TRUE
J 0
(-6100 1325);
DISPLAY 1.170213 (-6100 1325);
PAINT GREEN (-6100 1325);
DISPLAY INVISIBLE (-6100 1325);
FORCEPROP 1 LAST COMMENT_BODY TRUE
J 0
(-6325 1375);
DISPLAY 1.170213 (-6325 1375);
PAINT GREEN (-6325 1375);
DISPLAY INVISIBLE (-6325 1375);
FORCEPROP 2 LAST PATH I4
J 0
(-6375 1525);
DISPLAY 1.021277 (-6375 1525);
PAINT ORANGE (-6375 1525);
DISPLAY INVISIBLE (-6375 1525);
FORCEADD TAP..6
(-5575 2400);
FORCEPROP 3 LASTPIN (-5525 2400) SIG_NAME M_J_DQ<18>
J 0
(-5515 2410);
DISPLAY 0.659574 (-5515 2410);
PAINT MONO (-5515 2410);
DISPLAY INVISIBLE (-5515 2410);
FORCEPROP 1 LASTPIN (-5525 2400) BN 18
J 0
(-5577 2408);
DISPLAY 0.617021 (-5577 2408);
PAINT GREEN (-5577 2408);
FORCEPROP 2 LAST CDS_LIB mstr_standard
J 0
(-5575 2400);
PAINT MONO (-5575 2400);
DISPLAY INVISIBLE (-5575 2400);
FORCEPROP 1 LAST BODY_TYPE PLUMBING
J 0
(-5575 2350);
DISPLAY 1.595745 (-5575 2350);
PAINT GREEN (-5575 2350);
DISPLAY INVISIBLE (-5575 2350);
FORCEPROP 1 LAST HDL_TAP TRUE
J 0
(-5250 2275);
DISPLAY 1.595745 (-5250 2275);
PAINT GREEN (-5250 2275);
DISPLAY INVISIBLE (-5250 2275);
FORCEPROP 1 LAST PATH I40
J 0
(-5577 2400);
DISPLAY 0.872340 (-5577 2400);
PAINT GREEN (-5577 2400);
DISPLAY INVISIBLE (-5577 2400);
FORCEADD TAP..6
(-5575 2450);
FORCEPROP 3 LASTPIN (-5525 2450) SIG_NAME M_J_DQ<19>
J 0
(-5515 2460);
DISPLAY 0.659574 (-5515 2460);
PAINT MONO (-5515 2460);
DISPLAY INVISIBLE (-5515 2460);
FORCEPROP 1 LASTPIN (-5525 2450) BN 19
J 0
(-5577 2458);
DISPLAY 0.617021 (-5577 2458);
PAINT GREEN (-5577 2458);
FORCEPROP 2 LAST CDS_LIB mstr_standard
J 0
(-5575 2450);
PAINT MONO (-5575 2450);
DISPLAY INVISIBLE (-5575 2450);
FORCEPROP 1 LAST BODY_TYPE PLUMBING
J 0
(-5575 2400);
DISPLAY 1.595745 (-5575 2400);
PAINT GREEN (-5575 2400);
DISPLAY INVISIBLE (-5575 2400);
FORCEPROP 1 LAST HDL_TAP TRUE
J 0
(-5250 2325);
DISPLAY 1.595745 (-5250 2325);
PAINT GREEN (-5250 2325);
DISPLAY INVISIBLE (-5250 2325);
FORCEPROP 1 LAST PATH I41
J 0
(-5577 2450);
DISPLAY 0.872340 (-5577 2450);
PAINT GREEN (-5577 2450);
DISPLAY INVISIBLE (-5577 2450);
FORCEADD TAP..6
(-5575 2500);
FORCEPROP 3 LASTPIN (-5525 2500) SIG_NAME M_J_DQ<20>
J 0
(-5515 2510);
DISPLAY 0.659574 (-5515 2510);
PAINT MONO (-5515 2510);
DISPLAY INVISIBLE (-5515 2510);
FORCEPROP 1 LASTPIN (-5525 2500) BN 20
J 0
(-5577 2508);
DISPLAY 0.617021 (-5577 2508);
PAINT GREEN (-5577 2508);
FORCEPROP 2 LAST CDS_LIB mstr_standard
J 0
(-5575 2500);
PAINT MONO (-5575 2500);
DISPLAY INVISIBLE (-5575 2500);
FORCEPROP 1 LAST BODY_TYPE PLUMBING
J 0
(-5575 2450);
DISPLAY 1.595745 (-5575 2450);
PAINT GREEN (-5575 2450);
DISPLAY INVISIBLE (-5575 2450);
FORCEPROP 1 LAST HDL_TAP TRUE
J 0
(-5250 2375);
DISPLAY 1.595745 (-5250 2375);
PAINT GREEN (-5250 2375);
DISPLAY INVISIBLE (-5250 2375);
FORCEPROP 1 LAST PATH I42
J 0
(-5577 2500);
DISPLAY 0.872340 (-5577 2500);
PAINT GREEN (-5577 2500);
DISPLAY INVISIBLE (-5577 2500);
FORCEADD TAP..6
(-5575 2550);
FORCEPROP 3 LASTPIN (-5525 2550) SIG_NAME M_J_DQ<21>
J 0
(-5515 2560);
DISPLAY 0.659574 (-5515 2560);
PAINT MONO (-5515 2560);
DISPLAY INVISIBLE (-5515 2560);
FORCEPROP 1 LASTPIN (-5525 2550) BN 21
J 0
(-5577 2558);
DISPLAY 0.617021 (-5577 2558);
PAINT GREEN (-5577 2558);
FORCEPROP 2 LAST CDS_LIB mstr_standard
J 0
(-5575 2550);
PAINT MONO (-5575 2550);
DISPLAY INVISIBLE (-5575 2550);
FORCEPROP 1 LAST BODY_TYPE PLUMBING
J 0
(-5575 2500);
DISPLAY 1.595745 (-5575 2500);
PAINT GREEN (-5575 2500);
DISPLAY INVISIBLE (-5575 2500);
FORCEPROP 1 LAST HDL_TAP TRUE
J 0
(-5250 2425);
DISPLAY 1.595745 (-5250 2425);
PAINT GREEN (-5250 2425);
DISPLAY INVISIBLE (-5250 2425);
FORCEPROP 1 LAST PATH I43
J 0
(-5577 2550);
DISPLAY 0.872340 (-5577 2550);
PAINT GREEN (-5577 2550);
DISPLAY INVISIBLE (-5577 2550);
FORCEADD TAP..6
(-5575 2600);
FORCEPROP 3 LASTPIN (-5525 2600) SIG_NAME M_J_DQ<22>
J 0
(-5515 2610);
DISPLAY 0.659574 (-5515 2610);
PAINT MONO (-5515 2610);
DISPLAY INVISIBLE (-5515 2610);
FORCEPROP 1 LASTPIN (-5525 2600) BN 22
J 0
(-5577 2608);
DISPLAY 0.617021 (-5577 2608);
PAINT GREEN (-5577 2608);
FORCEPROP 2 LAST CDS_LIB mstr_standard
J 0
(-5575 2600);
PAINT MONO (-5575 2600);
DISPLAY INVISIBLE (-5575 2600);
FORCEPROP 1 LAST BODY_TYPE PLUMBING
J 0
(-5575 2550);
DISPLAY 1.595745 (-5575 2550);
PAINT GREEN (-5575 2550);
DISPLAY INVISIBLE (-5575 2550);
FORCEPROP 1 LAST HDL_TAP TRUE
J 0
(-5250 2475);
DISPLAY 1.595745 (-5250 2475);
PAINT GREEN (-5250 2475);
DISPLAY INVISIBLE (-5250 2475);
FORCEPROP 1 LAST PATH I44
J 0
(-5577 2600);
DISPLAY 0.872340 (-5577 2600);
PAINT GREEN (-5577 2600);
DISPLAY INVISIBLE (-5577 2600);
FORCEADD TAP..6
(-5575 2650);
FORCEPROP 3 LASTPIN (-5525 2650) SIG_NAME M_J_DQ<23>
J 0
(-5515 2660);
DISPLAY 0.659574 (-5515 2660);
PAINT MONO (-5515 2660);
DISPLAY INVISIBLE (-5515 2660);
FORCEPROP 1 LASTPIN (-5525 2650) BN 23
J 0
(-5577 2658);
DISPLAY 0.617021 (-5577 2658);
PAINT GREEN (-5577 2658);
FORCEPROP 2 LAST CDS_LIB mstr_standard
J 0
(-5575 2650);
PAINT MONO (-5575 2650);
DISPLAY INVISIBLE (-5575 2650);
FORCEPROP 1 LAST BODY_TYPE PLUMBING
J 0
(-5575 2600);
DISPLAY 1.595745 (-5575 2600);
PAINT GREEN (-5575 2600);
DISPLAY INVISIBLE (-5575 2600);
FORCEPROP 1 LAST HDL_TAP TRUE
J 0
(-5250 2525);
DISPLAY 1.595745 (-5250 2525);
PAINT GREEN (-5250 2525);
DISPLAY INVISIBLE (-5250 2525);
FORCEPROP 1 LAST PATH I45
J 0
(-5577 2650);
DISPLAY 0.872340 (-5577 2650);
PAINT GREEN (-5577 2650);
DISPLAY INVISIBLE (-5577 2650);
FORCEADD TAP..6
(-5575 2700);
FORCEPROP 3 LASTPIN (-5525 2700) SIG_NAME M_J_DQ<24>
J 0
(-5515 2710);
DISPLAY 0.659574 (-5515 2710);
PAINT MONO (-5515 2710);
DISPLAY INVISIBLE (-5515 2710);
FORCEPROP 1 LASTPIN (-5525 2700) BN 24
J 0
(-5577 2708);
DISPLAY 0.617021 (-5577 2708);
PAINT GREEN (-5577 2708);
FORCEPROP 2 LAST CDS_LIB mstr_standard
J 0
(-5575 2700);
PAINT MONO (-5575 2700);
DISPLAY INVISIBLE (-5575 2700);
FORCEPROP 1 LAST BODY_TYPE PLUMBING
J 0
(-5575 2650);
DISPLAY 1.595745 (-5575 2650);
PAINT GREEN (-5575 2650);
DISPLAY INVISIBLE (-5575 2650);
FORCEPROP 1 LAST HDL_TAP TRUE
J 0
(-5250 2575);
DISPLAY 1.595745 (-5250 2575);
PAINT GREEN (-5250 2575);
DISPLAY INVISIBLE (-5250 2575);
FORCEPROP 1 LAST PATH I46
J 0
(-5577 2700);
DISPLAY 0.872340 (-5577 2700);
PAINT GREEN (-5577 2700);
DISPLAY INVISIBLE (-5577 2700);
FORCEADD TAP..6
(-5575 2800);
FORCEPROP 3 LASTPIN (-5525 2800) SIG_NAME M_J_DQ<26>
J 0
(-5515 2810);
DISPLAY 0.659574 (-5515 2810);
PAINT MONO (-5515 2810);
DISPLAY INVISIBLE (-5515 2810);
FORCEPROP 1 LASTPIN (-5525 2800) BN 26
J 0
(-5577 2808);
DISPLAY 0.617021 (-5577 2808);
PAINT GREEN (-5577 2808);
FORCEPROP 2 LAST CDS_LIB mstr_standard
J 0
(-5575 2800);
PAINT MONO (-5575 2800);
DISPLAY INVISIBLE (-5575 2800);
FORCEPROP 1 LAST BODY_TYPE PLUMBING
J 0
(-5575 2750);
DISPLAY 1.595745 (-5575 2750);
PAINT GREEN (-5575 2750);
DISPLAY INVISIBLE (-5575 2750);
FORCEPROP 1 LAST HDL_TAP TRUE
J 0
(-5250 2675);
DISPLAY 1.595745 (-5250 2675);
PAINT GREEN (-5250 2675);
DISPLAY INVISIBLE (-5250 2675);
FORCEPROP 1 LAST PATH I47
J 0
(-5577 2800);
DISPLAY 0.872340 (-5577 2800);
PAINT GREEN (-5577 2800);
DISPLAY INVISIBLE (-5577 2800);
FORCEADD TAP..6
(-5575 2750);
FORCEPROP 3 LASTPIN (-5525 2750) SIG_NAME M_J_DQ<25>
J 0
(-5515 2760);
DISPLAY 0.659574 (-5515 2760);
PAINT MONO (-5515 2760);
DISPLAY INVISIBLE (-5515 2760);
FORCEPROP 1 LASTPIN (-5525 2750) BN 25
J 0
(-5577 2758);
DISPLAY 0.617021 (-5577 2758);
PAINT GREEN (-5577 2758);
FORCEPROP 2 LAST CDS_LIB mstr_standard
J 0
(-5575 2750);
PAINT MONO (-5575 2750);
DISPLAY INVISIBLE (-5575 2750);
FORCEPROP 1 LAST BODY_TYPE PLUMBING
J 0
(-5575 2700);
DISPLAY 1.595745 (-5575 2700);
PAINT GREEN (-5575 2700);
DISPLAY INVISIBLE (-5575 2700);
FORCEPROP 1 LAST HDL_TAP TRUE
J 0
(-5250 2625);
DISPLAY 1.595745 (-5250 2625);
PAINT GREEN (-5250 2625);
DISPLAY INVISIBLE (-5250 2625);
FORCEPROP 1 LAST PATH I48
J 0
(-5577 2750);
DISPLAY 0.872340 (-5577 2750);
PAINT GREEN (-5577 2750);
DISPLAY INVISIBLE (-5577 2750);
FORCEADD TAP..6
(-5575 2850);
FORCEPROP 3 LASTPIN (-5525 2850) SIG_NAME M_J_DQ<27>
J 0
(-5515 2860);
DISPLAY 0.659574 (-5515 2860);
PAINT MONO (-5515 2860);
DISPLAY INVISIBLE (-5515 2860);
FORCEPROP 1 LASTPIN (-5525 2850) BN 27
J 0
(-5577 2858);
DISPLAY 0.617021 (-5577 2858);
PAINT GREEN (-5577 2858);
FORCEPROP 2 LAST CDS_LIB mstr_standard
J 0
(-5575 2850);
PAINT MONO (-5575 2850);
DISPLAY INVISIBLE (-5575 2850);
FORCEPROP 1 LAST BODY_TYPE PLUMBING
J 0
(-5575 2800);
DISPLAY 1.595745 (-5575 2800);
PAINT GREEN (-5575 2800);
DISPLAY INVISIBLE (-5575 2800);
FORCEPROP 1 LAST HDL_TAP TRUE
J 0
(-5250 2725);
DISPLAY 1.595745 (-5250 2725);
PAINT GREEN (-5250 2725);
DISPLAY INVISIBLE (-5250 2725);
FORCEPROP 1 LAST PATH I49
J 0
(-5577 2850);
DISPLAY 0.872340 (-5577 2850);
PAINT GREEN (-5577 2850);
DISPLAY INVISIBLE (-5577 2850);
FORCEADD TAP..6
(-5575 600);
FORCEPROP 3 LASTPIN (-5525 600) SIG_NAME M_J_CLK_DN<0>
J 0
(-5515 610);
DISPLAY 0.659574 (-5515 610);
PAINT MONO (-5515 610);
DISPLAY INVISIBLE (-5515 610);
FORCEPROP 1 LASTPIN (-5525 600) BN 0
J 0
(-5577 608);
DISPLAY 0.617021 (-5577 608);
PAINT GREEN (-5577 608);
FORCEPROP 2 LAST CDS_LIB mstr_standard
J 0
(-5575 600);
PAINT MONO (-5575 600);
DISPLAY INVISIBLE (-5575 600);
FORCEPROP 1 LAST BODY_TYPE PLUMBING
J 0
(-5575 550);
DISPLAY 1.595745 (-5575 550);
PAINT GREEN (-5575 550);
DISPLAY INVISIBLE (-5575 550);
FORCEPROP 1 LAST HDL_TAP TRUE
J 0
(-5250 475);
DISPLAY 1.595745 (-5250 475);
PAINT GREEN (-5250 475);
DISPLAY INVISIBLE (-5250 475);
FORCEPROP 1 LAST PATH I5
J 0
(-5577 600);
DISPLAY 0.872340 (-5577 600);
PAINT GREEN (-5577 600);
DISPLAY INVISIBLE (-5577 600);
FORCEADD TAP..6
(-5575 2900);
FORCEPROP 3 LASTPIN (-5525 2900) SIG_NAME M_J_DQ<28>
J 0
(-5515 2910);
DISPLAY 0.659574 (-5515 2910);
PAINT MONO (-5515 2910);
DISPLAY INVISIBLE (-5515 2910);
FORCEPROP 1 LASTPIN (-5525 2900) BN 28
J 0
(-5577 2908);
DISPLAY 0.617021 (-5577 2908);
PAINT GREEN (-5577 2908);
FORCEPROP 2 LAST CDS_LIB mstr_standard
J 0
(-5575 2900);
PAINT MONO (-5575 2900);
DISPLAY INVISIBLE (-5575 2900);
FORCEPROP 1 LAST BODY_TYPE PLUMBING
J 0
(-5575 2850);
DISPLAY 1.595745 (-5575 2850);
PAINT GREEN (-5575 2850);
DISPLAY INVISIBLE (-5575 2850);
FORCEPROP 1 LAST HDL_TAP TRUE
J 0
(-5250 2775);
DISPLAY 1.595745 (-5250 2775);
PAINT GREEN (-5250 2775);
DISPLAY INVISIBLE (-5250 2775);
FORCEPROP 1 LAST PATH I50
J 0
(-5577 2900);
DISPLAY 0.872340 (-5577 2900);
PAINT GREEN (-5577 2900);
DISPLAY INVISIBLE (-5577 2900);
FORCEADD TAP..6
(-5575 2950);
FORCEPROP 3 LASTPIN (-5525 2950) SIG_NAME M_J_DQ<29>
J 0
(-5515 2960);
DISPLAY 0.659574 (-5515 2960);
PAINT MONO (-5515 2960);
DISPLAY INVISIBLE (-5515 2960);
FORCEPROP 1 LASTPIN (-5525 2950) BN 29
J 0
(-5577 2958);
DISPLAY 0.617021 (-5577 2958);
PAINT GREEN (-5577 2958);
FORCEPROP 2 LAST CDS_LIB mstr_standard
J 0
(-5575 2950);
PAINT MONO (-5575 2950);
DISPLAY INVISIBLE (-5575 2950);
FORCEPROP 1 LAST BODY_TYPE PLUMBING
J 0
(-5575 2900);
DISPLAY 1.595745 (-5575 2900);
PAINT GREEN (-5575 2900);
DISPLAY INVISIBLE (-5575 2900);
FORCEPROP 1 LAST HDL_TAP TRUE
J 0
(-5250 2825);
DISPLAY 1.595745 (-5250 2825);
PAINT GREEN (-5250 2825);
DISPLAY INVISIBLE (-5250 2825);
FORCEPROP 1 LAST PATH I51
J 0
(-5577 2950);
DISPLAY 0.872340 (-5577 2950);
PAINT GREEN (-5577 2950);
DISPLAY INVISIBLE (-5577 2950);
FORCEADD TAP..6
(-5575 3050);
FORCEPROP 3 LASTPIN (-5525 3050) SIG_NAME M_J_DQ<31>
J 0
(-5515 3060);
DISPLAY 0.659574 (-5515 3060);
PAINT MONO (-5515 3060);
DISPLAY INVISIBLE (-5515 3060);
FORCEPROP 1 LASTPIN (-5525 3050) BN 31
J 0
(-5577 3058);
DISPLAY 0.617021 (-5577 3058);
PAINT GREEN (-5577 3058);
FORCEPROP 2 LAST CDS_LIB mstr_standard
J 0
(-5575 3050);
PAINT MONO (-5575 3050);
DISPLAY INVISIBLE (-5575 3050);
FORCEPROP 1 LAST BODY_TYPE PLUMBING
J 0
(-5575 3000);
DISPLAY 1.595745 (-5575 3000);
PAINT GREEN (-5575 3000);
DISPLAY INVISIBLE (-5575 3000);
FORCEPROP 1 LAST HDL_TAP TRUE
J 0
(-5250 2925);
DISPLAY 1.595745 (-5250 2925);
PAINT GREEN (-5250 2925);
DISPLAY INVISIBLE (-5250 2925);
FORCEPROP 1 LAST PATH I52
J 0
(-5577 3050);
DISPLAY 0.872340 (-5577 3050);
PAINT GREEN (-5577 3050);
DISPLAY INVISIBLE (-5577 3050);
FORCEADD TAP..6
(-5575 3000);
FORCEPROP 3 LASTPIN (-5525 3000) SIG_NAME M_J_DQ<30>
J 0
(-5515 3010);
DISPLAY 0.659574 (-5515 3010);
PAINT MONO (-5515 3010);
DISPLAY INVISIBLE (-5515 3010);
FORCEPROP 1 LASTPIN (-5525 3000) BN 30
J 0
(-5577 3008);
DISPLAY 0.617021 (-5577 3008);
PAINT GREEN (-5577 3008);
FORCEPROP 2 LAST CDS_LIB mstr_standard
J 0
(-5575 3000);
PAINT MONO (-5575 3000);
DISPLAY INVISIBLE (-5575 3000);
FORCEPROP 1 LAST BODY_TYPE PLUMBING
J 0
(-5575 2950);
DISPLAY 1.595745 (-5575 2950);
PAINT GREEN (-5575 2950);
DISPLAY INVISIBLE (-5575 2950);
FORCEPROP 1 LAST HDL_TAP TRUE
J 0
(-5250 2875);
DISPLAY 1.595745 (-5250 2875);
PAINT GREEN (-5250 2875);
DISPLAY INVISIBLE (-5250 2875);
FORCEPROP 1 LAST PATH I53
J 0
(-5577 3000);
DISPLAY 0.872340 (-5577 3000);
PAINT GREEN (-5577 3000);
DISPLAY INVISIBLE (-5577 3000);
FORCEADD TAP..6
(-5575 3100);
FORCEPROP 3 LASTPIN (-5525 3100) SIG_NAME M_J_DQ<32>
J 0
(-5515 3110);
DISPLAY 0.659574 (-5515 3110);
PAINT MONO (-5515 3110);
DISPLAY INVISIBLE (-5515 3110);
FORCEPROP 1 LASTPIN (-5525 3100) BN 32
J 0
(-5577 3108);
DISPLAY 0.617021 (-5577 3108);
PAINT GREEN (-5577 3108);
FORCEPROP 2 LAST CDS_LIB mstr_standard
J 0
(-5575 3100);
PAINT MONO (-5575 3100);
DISPLAY INVISIBLE (-5575 3100);
FORCEPROP 1 LAST BODY_TYPE PLUMBING
J 0
(-5575 3050);
DISPLAY 1.595745 (-5575 3050);
PAINT GREEN (-5575 3050);
DISPLAY INVISIBLE (-5575 3050);
FORCEPROP 1 LAST HDL_TAP TRUE
J 0
(-5250 2975);
DISPLAY 1.595745 (-5250 2975);
PAINT GREEN (-5250 2975);
DISPLAY INVISIBLE (-5250 2975);
FORCEPROP 1 LAST PATH I54
J 0
(-5577 3100);
DISPLAY 0.872340 (-5577 3100);
PAINT GREEN (-5577 3100);
DISPLAY INVISIBLE (-5577 3100);
FORCEADD TAP..6
(-5575 3150);
FORCEPROP 3 LASTPIN (-5525 3150) SIG_NAME M_J_DQ<33>
J 0
(-5515 3160);
DISPLAY 0.659574 (-5515 3160);
PAINT MONO (-5515 3160);
DISPLAY INVISIBLE (-5515 3160);
FORCEPROP 1 LASTPIN (-5525 3150) BN 33
J 0
(-5577 3158);
DISPLAY 0.617021 (-5577 3158);
PAINT GREEN (-5577 3158);
FORCEPROP 2 LAST CDS_LIB mstr_standard
J 0
(-5575 3150);
PAINT MONO (-5575 3150);
DISPLAY INVISIBLE (-5575 3150);
FORCEPROP 1 LAST BODY_TYPE PLUMBING
J 0
(-5575 3100);
DISPLAY 1.595745 (-5575 3100);
PAINT GREEN (-5575 3100);
DISPLAY INVISIBLE (-5575 3100);
FORCEPROP 1 LAST HDL_TAP TRUE
J 0
(-5250 3025);
DISPLAY 1.595745 (-5250 3025);
PAINT GREEN (-5250 3025);
DISPLAY INVISIBLE (-5250 3025);
FORCEPROP 1 LAST PATH I55
J 0
(-5577 3150);
DISPLAY 0.872340 (-5577 3150);
PAINT GREEN (-5577 3150);
DISPLAY INVISIBLE (-5577 3150);
FORCEADD TAP..6
(-5575 3200);
FORCEPROP 3 LASTPIN (-5525 3200) SIG_NAME M_J_DQ<34>
J 0
(-5515 3210);
DISPLAY 0.659574 (-5515 3210);
PAINT MONO (-5515 3210);
DISPLAY INVISIBLE (-5515 3210);
FORCEPROP 1 LASTPIN (-5525 3200) BN 34
J 0
(-5577 3208);
DISPLAY 0.617021 (-5577 3208);
PAINT GREEN (-5577 3208);
FORCEPROP 2 LAST CDS_LIB mstr_standard
J 0
(-5575 3200);
PAINT MONO (-5575 3200);
DISPLAY INVISIBLE (-5575 3200);
FORCEPROP 1 LAST BODY_TYPE PLUMBING
J 0
(-5575 3150);
DISPLAY 1.595745 (-5575 3150);
PAINT GREEN (-5575 3150);
DISPLAY INVISIBLE (-5575 3150);
FORCEPROP 1 LAST HDL_TAP TRUE
J 0
(-5250 3075);
DISPLAY 1.595745 (-5250 3075);
PAINT GREEN (-5250 3075);
DISPLAY INVISIBLE (-5250 3075);
FORCEPROP 1 LAST PATH I56
J 0
(-5577 3200);
DISPLAY 0.872340 (-5577 3200);
PAINT GREEN (-5577 3200);
DISPLAY INVISIBLE (-5577 3200);
FORCEADD TAP..6
(-5575 3300);
FORCEPROP 3 LASTPIN (-5525 3300) SIG_NAME M_J_DQ<36>
J 0
(-5515 3310);
DISPLAY 0.659574 (-5515 3310);
PAINT MONO (-5515 3310);
DISPLAY INVISIBLE (-5515 3310);
FORCEPROP 1 LASTPIN (-5525 3300) BN 36
J 0
(-5577 3308);
DISPLAY 0.617021 (-5577 3308);
PAINT GREEN (-5577 3308);
FORCEPROP 2 LAST CDS_LIB mstr_standard
J 0
(-5575 3300);
PAINT MONO (-5575 3300);
DISPLAY INVISIBLE (-5575 3300);
FORCEPROP 1 LAST BODY_TYPE PLUMBING
J 0
(-5575 3250);
DISPLAY 1.595745 (-5575 3250);
PAINT GREEN (-5575 3250);
DISPLAY INVISIBLE (-5575 3250);
FORCEPROP 1 LAST HDL_TAP TRUE
J 0
(-5250 3175);
DISPLAY 1.595745 (-5250 3175);
PAINT GREEN (-5250 3175);
DISPLAY INVISIBLE (-5250 3175);
FORCEPROP 1 LAST PATH I57
J 0
(-5577 3300);
DISPLAY 0.872340 (-5577 3300);
PAINT GREEN (-5577 3300);
DISPLAY INVISIBLE (-5577 3300);
FORCEADD TAP..6
(-5575 3250);
FORCEPROP 3 LASTPIN (-5525 3250) SIG_NAME M_J_DQ<35>
J 0
(-5515 3260);
DISPLAY 0.659574 (-5515 3260);
PAINT MONO (-5515 3260);
DISPLAY INVISIBLE (-5515 3260);
FORCEPROP 1 LASTPIN (-5525 3250) BN 35
J 0
(-5577 3258);
DISPLAY 0.617021 (-5577 3258);
PAINT GREEN (-5577 3258);
FORCEPROP 2 LAST CDS_LIB mstr_standard
J 0
(-5575 3250);
PAINT MONO (-5575 3250);
DISPLAY INVISIBLE (-5575 3250);
FORCEPROP 1 LAST BODY_TYPE PLUMBING
J 0
(-5575 3200);
DISPLAY 1.595745 (-5575 3200);
PAINT GREEN (-5575 3200);
DISPLAY INVISIBLE (-5575 3200);
FORCEPROP 1 LAST HDL_TAP TRUE
J 0
(-5250 3125);
DISPLAY 1.595745 (-5250 3125);
PAINT GREEN (-5250 3125);
DISPLAY INVISIBLE (-5250 3125);
FORCEPROP 1 LAST PATH I58
J 0
(-5577 3250);
DISPLAY 0.872340 (-5577 3250);
PAINT GREEN (-5577 3250);
DISPLAY INVISIBLE (-5577 3250);
FORCEADD TAP..6
(-5575 3350);
FORCEPROP 3 LASTPIN (-5525 3350) SIG_NAME M_J_DQ<37>
J 0
(-5515 3360);
DISPLAY 0.659574 (-5515 3360);
PAINT MONO (-5515 3360);
DISPLAY INVISIBLE (-5515 3360);
FORCEPROP 1 LASTPIN (-5525 3350) BN 37
J 0
(-5577 3358);
DISPLAY 0.617021 (-5577 3358);
PAINT GREEN (-5577 3358);
FORCEPROP 2 LAST CDS_LIB mstr_standard
J 0
(-5575 3350);
PAINT MONO (-5575 3350);
DISPLAY INVISIBLE (-5575 3350);
FORCEPROP 1 LAST BODY_TYPE PLUMBING
J 0
(-5575 3300);
DISPLAY 1.595745 (-5575 3300);
PAINT GREEN (-5575 3300);
DISPLAY INVISIBLE (-5575 3300);
FORCEPROP 1 LAST HDL_TAP TRUE
J 0
(-5250 3225);
DISPLAY 1.595745 (-5250 3225);
PAINT GREEN (-5250 3225);
DISPLAY INVISIBLE (-5250 3225);
FORCEPROP 1 LAST PATH I59
J 0
(-5577 3350);
DISPLAY 0.872340 (-5577 3350);
PAINT GREEN (-5577 3350);
DISPLAY INVISIBLE (-5577 3350);
FORCEADD TAP..6
(-5575 650);
FORCEPROP 3 LASTPIN (-5525 650) SIG_NAME M_J_CLK_DN<1>
J 0
(-5515 660);
DISPLAY 0.659574 (-5515 660);
PAINT MONO (-5515 660);
DISPLAY INVISIBLE (-5515 660);
FORCEPROP 1 LASTPIN (-5525 650) BN 1
J 0
(-5577 658);
DISPLAY 0.617021 (-5577 658);
PAINT GREEN (-5577 658);
FORCEPROP 2 LAST CDS_LIB mstr_standard
J 0
(-5575 650);
PAINT MONO (-5575 650);
DISPLAY INVISIBLE (-5575 650);
FORCEPROP 1 LAST BODY_TYPE PLUMBING
J 0
(-5575 600);
DISPLAY 1.595745 (-5575 600);
PAINT GREEN (-5575 600);
DISPLAY INVISIBLE (-5575 600);
FORCEPROP 1 LAST HDL_TAP TRUE
J 0
(-5250 525);
DISPLAY 1.595745 (-5250 525);
PAINT GREEN (-5250 525);
DISPLAY INVISIBLE (-5250 525);
FORCEPROP 1 LAST PATH I6
J 0
(-5577 650);
DISPLAY 0.872340 (-5577 650);
PAINT GREEN (-5577 650);
DISPLAY INVISIBLE (-5577 650);
FORCEADD TAP..6
(-5575 3400);
FORCEPROP 3 LASTPIN (-5525 3400) SIG_NAME M_J_DQ<38>
J 0
(-5515 3410);
DISPLAY 0.659574 (-5515 3410);
PAINT MONO (-5515 3410);
DISPLAY INVISIBLE (-5515 3410);
FORCEPROP 1 LASTPIN (-5525 3400) BN 38
J 0
(-5577 3408);
DISPLAY 0.617021 (-5577 3408);
PAINT GREEN (-5577 3408);
FORCEPROP 2 LAST CDS_LIB mstr_standard
J 0
(-5575 3400);
PAINT MONO (-5575 3400);
DISPLAY INVISIBLE (-5575 3400);
FORCEPROP 1 LAST BODY_TYPE PLUMBING
J 0
(-5575 3350);
DISPLAY 1.595745 (-5575 3350);
PAINT GREEN (-5575 3350);
DISPLAY INVISIBLE (-5575 3350);
FORCEPROP 1 LAST HDL_TAP TRUE
J 0
(-5250 3275);
DISPLAY 1.595745 (-5250 3275);
PAINT GREEN (-5250 3275);
DISPLAY INVISIBLE (-5250 3275);
FORCEPROP 1 LAST PATH I60
J 0
(-5577 3400);
DISPLAY 0.872340 (-5577 3400);
PAINT GREEN (-5577 3400);
DISPLAY INVISIBLE (-5577 3400);
FORCEADD TAP..6
(-5575 3450);
FORCEPROP 3 LASTPIN (-5525 3450) SIG_NAME M_J_DQ<39>
J 0
(-5515 3460);
DISPLAY 0.659574 (-5515 3460);
PAINT MONO (-5515 3460);
DISPLAY INVISIBLE (-5515 3460);
FORCEPROP 1 LASTPIN (-5525 3450) BN 39
J 0
(-5577 3458);
DISPLAY 0.617021 (-5577 3458);
PAINT GREEN (-5577 3458);
FORCEPROP 2 LAST CDS_LIB mstr_standard
J 0
(-5575 3450);
PAINT MONO (-5575 3450);
DISPLAY INVISIBLE (-5575 3450);
FORCEPROP 1 LAST BODY_TYPE PLUMBING
J 0
(-5575 3400);
DISPLAY 1.595745 (-5575 3400);
PAINT GREEN (-5575 3400);
DISPLAY INVISIBLE (-5575 3400);
FORCEPROP 1 LAST HDL_TAP TRUE
J 0
(-5250 3325);
DISPLAY 1.595745 (-5250 3325);
PAINT GREEN (-5250 3325);
DISPLAY INVISIBLE (-5250 3325);
FORCEPROP 1 LAST PATH I61
J 0
(-5577 3450);
DISPLAY 0.872340 (-5577 3450);
PAINT GREEN (-5577 3450);
DISPLAY INVISIBLE (-5577 3450);
FORCEADD TAP..6
(-5575 3500);
FORCEPROP 3 LASTPIN (-5525 3500) SIG_NAME M_J_DQ<40>
J 0
(-5515 3510);
DISPLAY 0.659574 (-5515 3510);
PAINT MONO (-5515 3510);
DISPLAY INVISIBLE (-5515 3510);
FORCEPROP 1 LASTPIN (-5525 3500) BN 40
J 0
(-5577 3508);
DISPLAY 0.617021 (-5577 3508);
PAINT GREEN (-5577 3508);
FORCEPROP 2 LAST CDS_LIB mstr_standard
J 0
(-5575 3500);
PAINT MONO (-5575 3500);
DISPLAY INVISIBLE (-5575 3500);
FORCEPROP 1 LAST BODY_TYPE PLUMBING
J 0
(-5575 3450);
DISPLAY 1.595745 (-5575 3450);
PAINT GREEN (-5575 3450);
DISPLAY INVISIBLE (-5575 3450);
FORCEPROP 1 LAST HDL_TAP TRUE
J 0
(-5250 3375);
DISPLAY 1.595745 (-5250 3375);
PAINT GREEN (-5250 3375);
DISPLAY INVISIBLE (-5250 3375);
FORCEPROP 1 LAST PATH I62
J 0
(-5577 3500);
DISPLAY 0.872340 (-5577 3500);
PAINT GREEN (-5577 3500);
DISPLAY INVISIBLE (-5577 3500);
FORCEADD TAP..6
(-5575 3550);
FORCEPROP 3 LASTPIN (-5525 3550) SIG_NAME M_J_DQ<41>
J 0
(-5515 3560);
DISPLAY 0.659574 (-5515 3560);
PAINT MONO (-5515 3560);
DISPLAY INVISIBLE (-5515 3560);
FORCEPROP 1 LASTPIN (-5525 3550) BN 41
J 0
(-5577 3558);
DISPLAY 0.617021 (-5577 3558);
PAINT GREEN (-5577 3558);
FORCEPROP 2 LAST CDS_LIB mstr_standard
J 0
(-5575 3550);
PAINT MONO (-5575 3550);
DISPLAY INVISIBLE (-5575 3550);
FORCEPROP 1 LAST BODY_TYPE PLUMBING
J 0
(-5575 3500);
DISPLAY 1.595745 (-5575 3500);
PAINT GREEN (-5575 3500);
DISPLAY INVISIBLE (-5575 3500);
FORCEPROP 1 LAST HDL_TAP TRUE
J 0
(-5250 3425);
DISPLAY 1.595745 (-5250 3425);
PAINT GREEN (-5250 3425);
DISPLAY INVISIBLE (-5250 3425);
FORCEPROP 1 LAST PATH I63
J 0
(-5577 3550);
DISPLAY 0.872340 (-5577 3550);
PAINT GREEN (-5577 3550);
DISPLAY INVISIBLE (-5577 3550);
FORCEADD TAP..6
(-5575 3600);
FORCEPROP 3 LASTPIN (-5525 3600) SIG_NAME M_J_DQ<42>
J 0
(-5515 3610);
DISPLAY 0.659574 (-5515 3610);
PAINT MONO (-5515 3610);
DISPLAY INVISIBLE (-5515 3610);
FORCEPROP 1 LASTPIN (-5525 3600) BN 42
J 0
(-5577 3608);
DISPLAY 0.617021 (-5577 3608);
PAINT GREEN (-5577 3608);
FORCEPROP 2 LAST CDS_LIB mstr_standard
J 0
(-5575 3600);
PAINT MONO (-5575 3600);
DISPLAY INVISIBLE (-5575 3600);
FORCEPROP 1 LAST BODY_TYPE PLUMBING
J 0
(-5575 3550);
DISPLAY 1.595745 (-5575 3550);
PAINT GREEN (-5575 3550);
DISPLAY INVISIBLE (-5575 3550);
FORCEPROP 1 LAST HDL_TAP TRUE
J 0
(-5250 3475);
DISPLAY 1.595745 (-5250 3475);
PAINT GREEN (-5250 3475);
DISPLAY INVISIBLE (-5250 3475);
FORCEPROP 1 LAST PATH I64
J 0
(-5577 3600);
DISPLAY 0.872340 (-5577 3600);
PAINT GREEN (-5577 3600);
DISPLAY INVISIBLE (-5577 3600);
FORCEADD TAP..6
(-5575 3650);
FORCEPROP 3 LASTPIN (-5525 3650) SIG_NAME M_J_DQ<43>
J 0
(-5515 3660);
DISPLAY 0.659574 (-5515 3660);
PAINT MONO (-5515 3660);
DISPLAY INVISIBLE (-5515 3660);
FORCEPROP 1 LASTPIN (-5525 3650) BN 43
J 0
(-5577 3658);
DISPLAY 0.617021 (-5577 3658);
PAINT GREEN (-5577 3658);
FORCEPROP 2 LAST CDS_LIB mstr_standard
J 0
(-5575 3650);
PAINT MONO (-5575 3650);
DISPLAY INVISIBLE (-5575 3650);
FORCEPROP 1 LAST BODY_TYPE PLUMBING
J 0
(-5575 3600);
DISPLAY 1.595745 (-5575 3600);
PAINT GREEN (-5575 3600);
DISPLAY INVISIBLE (-5575 3600);
FORCEPROP 1 LAST HDL_TAP TRUE
J 0
(-5250 3525);
DISPLAY 1.595745 (-5250 3525);
PAINT GREEN (-5250 3525);
DISPLAY INVISIBLE (-5250 3525);
FORCEPROP 1 LAST PATH I65
J 0
(-5577 3650);
DISPLAY 0.872340 (-5577 3650);
PAINT GREEN (-5577 3650);
DISPLAY INVISIBLE (-5577 3650);
FORCEADD TAP..6
(-5575 3700);
FORCEPROP 3 LASTPIN (-5525 3700) SIG_NAME M_J_DQ<44>
J 0
(-5515 3710);
DISPLAY 0.659574 (-5515 3710);
PAINT MONO (-5515 3710);
DISPLAY INVISIBLE (-5515 3710);
FORCEPROP 1 LASTPIN (-5525 3700) BN 44
J 0
(-5577 3708);
DISPLAY 0.617021 (-5577 3708);
PAINT GREEN (-5577 3708);
FORCEPROP 2 LAST CDS_LIB mstr_standard
J 0
(-5575 3700);
PAINT MONO (-5575 3700);
DISPLAY INVISIBLE (-5575 3700);
FORCEPROP 1 LAST BODY_TYPE PLUMBING
J 0
(-5575 3650);
DISPLAY 1.595745 (-5575 3650);
PAINT GREEN (-5575 3650);
DISPLAY INVISIBLE (-5575 3650);
FORCEPROP 1 LAST HDL_TAP TRUE
J 0
(-5250 3575);
DISPLAY 1.595745 (-5250 3575);
PAINT GREEN (-5250 3575);
DISPLAY INVISIBLE (-5250 3575);
FORCEPROP 1 LAST PATH I66
J 0
(-5577 3700);
DISPLAY 0.872340 (-5577 3700);
PAINT GREEN (-5577 3700);
DISPLAY INVISIBLE (-5577 3700);
FORCEADD TAP..6
(-5575 3750);
FORCEPROP 3 LASTPIN (-5525 3750) SIG_NAME M_J_DQ<45>
J 0
(-5515 3760);
DISPLAY 0.659574 (-5515 3760);
PAINT MONO (-5515 3760);
DISPLAY INVISIBLE (-5515 3760);
FORCEPROP 1 LASTPIN (-5525 3750) BN 45
J 0
(-5577 3758);
DISPLAY 0.617021 (-5577 3758);
PAINT GREEN (-5577 3758);
FORCEPROP 2 LAST CDS_LIB mstr_standard
J 0
(-5575 3750);
PAINT MONO (-5575 3750);
DISPLAY INVISIBLE (-5575 3750);
FORCEPROP 1 LAST BODY_TYPE PLUMBING
J 0
(-5575 3700);
DISPLAY 1.595745 (-5575 3700);
PAINT GREEN (-5575 3700);
DISPLAY INVISIBLE (-5575 3700);
FORCEPROP 1 LAST HDL_TAP TRUE
J 0
(-5250 3625);
DISPLAY 1.595745 (-5250 3625);
PAINT GREEN (-5250 3625);
DISPLAY INVISIBLE (-5250 3625);
FORCEPROP 1 LAST PATH I67
J 0
(-5577 3750);
DISPLAY 0.872340 (-5577 3750);
PAINT GREEN (-5577 3750);
DISPLAY INVISIBLE (-5577 3750);
FORCEADD TAP..6
(-5575 3800);
FORCEPROP 3 LASTPIN (-5525 3800) SIG_NAME M_J_DQ<46>
J 0
(-5515 3810);
DISPLAY 0.659574 (-5515 3810);
PAINT MONO (-5515 3810);
DISPLAY INVISIBLE (-5515 3810);
FORCEPROP 1 LASTPIN (-5525 3800) BN 46
J 0
(-5577 3808);
DISPLAY 0.617021 (-5577 3808);
PAINT GREEN (-5577 3808);
FORCEPROP 2 LAST CDS_LIB mstr_standard
J 0
(-5575 3800);
PAINT MONO (-5575 3800);
DISPLAY INVISIBLE (-5575 3800);
FORCEPROP 1 LAST BODY_TYPE PLUMBING
J 0
(-5575 3750);
DISPLAY 1.595745 (-5575 3750);
PAINT GREEN (-5575 3750);
DISPLAY INVISIBLE (-5575 3750);
FORCEPROP 1 LAST HDL_TAP TRUE
J 0
(-5250 3675);
DISPLAY 1.595745 (-5250 3675);
PAINT GREEN (-5250 3675);
DISPLAY INVISIBLE (-5250 3675);
FORCEPROP 1 LAST PATH I68
J 0
(-5577 3800);
DISPLAY 0.872340 (-5577 3800);
PAINT GREEN (-5577 3800);
DISPLAY INVISIBLE (-5577 3800);
FORCEADD TAP..6
(-5575 3850);
FORCEPROP 3 LASTPIN (-5525 3850) SIG_NAME M_J_DQ<47>
J 0
(-5515 3860);
DISPLAY 0.659574 (-5515 3860);
PAINT MONO (-5515 3860);
DISPLAY INVISIBLE (-5515 3860);
FORCEPROP 1 LASTPIN (-5525 3850) BN 47
J 0
(-5577 3858);
DISPLAY 0.617021 (-5577 3858);
PAINT GREEN (-5577 3858);
FORCEPROP 2 LAST CDS_LIB mstr_standard
J 0
(-5575 3850);
PAINT MONO (-5575 3850);
DISPLAY INVISIBLE (-5575 3850);
FORCEPROP 1 LAST BODY_TYPE PLUMBING
J 0
(-5575 3800);
DISPLAY 1.595745 (-5575 3800);
PAINT GREEN (-5575 3800);
DISPLAY INVISIBLE (-5575 3800);
FORCEPROP 1 LAST HDL_TAP TRUE
J 0
(-5250 3725);
DISPLAY 1.595745 (-5250 3725);
PAINT GREEN (-5250 3725);
DISPLAY INVISIBLE (-5250 3725);
FORCEPROP 1 LAST PATH I69
J 0
(-5577 3850);
DISPLAY 0.872340 (-5577 3850);
PAINT GREEN (-5577 3850);
DISPLAY INVISIBLE (-5577 3850);
FORCEADD TAP..6
(-5575 750);
FORCEPROP 3 LASTPIN (-5525 750) SIG_NAME M_J_CLK_DN<3>
J 0
(-5515 760);
DISPLAY 0.659574 (-5515 760);
PAINT MONO (-5515 760);
DISPLAY INVISIBLE (-5515 760);
FORCEPROP 1 LASTPIN (-5525 750) BN 3
J 0
(-5577 758);
DISPLAY 0.617021 (-5577 758);
PAINT GREEN (-5577 758);
FORCEPROP 2 LAST CDS_LIB mstr_standard
J 0
(-5575 750);
PAINT MONO (-5575 750);
DISPLAY INVISIBLE (-5575 750);
FORCEPROP 1 LAST BODY_TYPE PLUMBING
J 0
(-5575 700);
DISPLAY 1.595745 (-5575 700);
PAINT GREEN (-5575 700);
DISPLAY INVISIBLE (-5575 700);
FORCEPROP 1 LAST HDL_TAP TRUE
J 0
(-5250 625);
DISPLAY 1.595745 (-5250 625);
PAINT GREEN (-5250 625);
DISPLAY INVISIBLE (-5250 625);
FORCEPROP 1 LAST PATH I7
J 0
(-5577 750);
DISPLAY 0.872340 (-5577 750);
PAINT GREEN (-5577 750);
DISPLAY INVISIBLE (-5577 750);
FORCEADD TAP..6
(-5575 3900);
FORCEPROP 3 LASTPIN (-5525 3900) SIG_NAME M_J_DQ<48>
J 0
(-5515 3910);
DISPLAY 0.659574 (-5515 3910);
PAINT MONO (-5515 3910);
DISPLAY INVISIBLE (-5515 3910);
FORCEPROP 1 LASTPIN (-5525 3900) BN 48
J 0
(-5577 3908);
DISPLAY 0.617021 (-5577 3908);
PAINT GREEN (-5577 3908);
FORCEPROP 2 LAST CDS_LIB mstr_standard
J 0
(-5575 3900);
PAINT MONO (-5575 3900);
DISPLAY INVISIBLE (-5575 3900);
FORCEPROP 1 LAST BODY_TYPE PLUMBING
J 0
(-5575 3850);
DISPLAY 1.595745 (-5575 3850);
PAINT GREEN (-5575 3850);
DISPLAY INVISIBLE (-5575 3850);
FORCEPROP 1 LAST HDL_TAP TRUE
J 0
(-5250 3775);
DISPLAY 1.595745 (-5250 3775);
PAINT GREEN (-5250 3775);
DISPLAY INVISIBLE (-5250 3775);
FORCEPROP 1 LAST PATH I70
J 0
(-5577 3900);
DISPLAY 0.872340 (-5577 3900);
PAINT GREEN (-5577 3900);
DISPLAY INVISIBLE (-5577 3900);
FORCEADD TAP..6
(-5575 3950);
FORCEPROP 3 LASTPIN (-5525 3950) SIG_NAME M_J_DQ<49>
J 0
(-5515 3960);
DISPLAY 0.659574 (-5515 3960);
PAINT MONO (-5515 3960);
DISPLAY INVISIBLE (-5515 3960);
FORCEPROP 1 LASTPIN (-5525 3950) BN 49
J 0
(-5577 3958);
DISPLAY 0.617021 (-5577 3958);
PAINT GREEN (-5577 3958);
FORCEPROP 2 LAST CDS_LIB mstr_standard
J 0
(-5575 3950);
PAINT MONO (-5575 3950);
DISPLAY INVISIBLE (-5575 3950);
FORCEPROP 1 LAST BODY_TYPE PLUMBING
J 0
(-5575 3900);
DISPLAY 1.595745 (-5575 3900);
PAINT GREEN (-5575 3900);
DISPLAY INVISIBLE (-5575 3900);
FORCEPROP 1 LAST HDL_TAP TRUE
J 0
(-5250 3825);
DISPLAY 1.595745 (-5250 3825);
PAINT GREEN (-5250 3825);
DISPLAY INVISIBLE (-5250 3825);
FORCEPROP 1 LAST PATH I71
J 0
(-5577 3950);
DISPLAY 0.872340 (-5577 3950);
PAINT GREEN (-5577 3950);
DISPLAY INVISIBLE (-5577 3950);
FORCEADD OFFPAGE..6
(-6425 4775);
FORCEPROP 2 LAST $XR0 81 
J 0
(-6674 4775);
DISPLAY 0.638298 (-6674 4775);
PAINT MONO (-6674 4775);
FORCEPROP 2 LAST $XR1 82 
J 0
(-6764 4775);
DISPLAY 0.638298 (-6764 4775);
PAINT MONO (-6764 4775);
FORCEPROP 2 LAST CDS_LIB mstr_standard
J 0
(-6425 4775);
PAINT MONO (-6425 4775);
DISPLAY INVISIBLE (-6425 4775);
FORCEPROP 1 LAST OFFPAGE TRUE
J 0
(-6100 4650);
DISPLAY 1.170213 (-6100 4650);
PAINT GREEN (-6100 4650);
DISPLAY INVISIBLE (-6100 4650);
FORCEPROP 1 LAST COMMENT_BODY TRUE
J 0
(-6325 4700);
DISPLAY 1.170213 (-6325 4700);
PAINT GREEN (-6325 4700);
DISPLAY INVISIBLE (-6325 4700);
FORCEPROP 2 LAST PATH I72
J 0
(-6375 4850);
DISPLAY 1.021277 (-6375 4850);
PAINT ORANGE (-6375 4850);
DISPLAY INVISIBLE (-6375 4850);
FORCEADD TAP..6
(-5575 4000);
FORCEPROP 3 LASTPIN (-5525 4000) SIG_NAME M_J_DQ<50>
J 0
(-5515 4010);
DISPLAY 0.659574 (-5515 4010);
PAINT MONO (-5515 4010);
DISPLAY INVISIBLE (-5515 4010);
FORCEPROP 1 LASTPIN (-5525 4000) BN 50
J 0
(-5577 4008);
DISPLAY 0.617021 (-5577 4008);
PAINT GREEN (-5577 4008);
FORCEPROP 2 LAST CDS_LIB mstr_standard
J 0
(-5575 4000);
PAINT MONO (-5575 4000);
DISPLAY INVISIBLE (-5575 4000);
FORCEPROP 1 LAST BODY_TYPE PLUMBING
J 0
(-5575 3950);
DISPLAY 1.595745 (-5575 3950);
PAINT GREEN (-5575 3950);
DISPLAY INVISIBLE (-5575 3950);
FORCEPROP 1 LAST HDL_TAP TRUE
J 0
(-5250 3875);
DISPLAY 1.595745 (-5250 3875);
PAINT GREEN (-5250 3875);
DISPLAY INVISIBLE (-5250 3875);
FORCEPROP 1 LAST PATH I73
J 0
(-5577 4000);
DISPLAY 0.872340 (-5577 4000);
PAINT GREEN (-5577 4000);
DISPLAY INVISIBLE (-5577 4000);
FORCEADD TAP..6
(-5575 4050);
FORCEPROP 3 LASTPIN (-5525 4050) SIG_NAME M_J_DQ<51>
J 0
(-5515 4060);
DISPLAY 0.659574 (-5515 4060);
PAINT MONO (-5515 4060);
DISPLAY INVISIBLE (-5515 4060);
FORCEPROP 1 LASTPIN (-5525 4050) BN 51
J 0
(-5577 4058);
DISPLAY 0.617021 (-5577 4058);
PAINT GREEN (-5577 4058);
FORCEPROP 2 LAST CDS_LIB mstr_standard
J 0
(-5575 4050);
PAINT MONO (-5575 4050);
DISPLAY INVISIBLE (-5575 4050);
FORCEPROP 1 LAST BODY_TYPE PLUMBING
J 0
(-5575 4000);
DISPLAY 1.595745 (-5575 4000);
PAINT GREEN (-5575 4000);
DISPLAY INVISIBLE (-5575 4000);
FORCEPROP 1 LAST HDL_TAP TRUE
J 0
(-5250 3925);
DISPLAY 1.595745 (-5250 3925);
PAINT GREEN (-5250 3925);
DISPLAY INVISIBLE (-5250 3925);
FORCEPROP 1 LAST PATH I74
J 0
(-5577 4050);
DISPLAY 0.872340 (-5577 4050);
PAINT GREEN (-5577 4050);
DISPLAY INVISIBLE (-5577 4050);
FORCEADD TAP..6
(-5575 4100);
FORCEPROP 3 LASTPIN (-5525 4100) SIG_NAME M_J_DQ<52>
J 0
(-5515 4110);
DISPLAY 0.659574 (-5515 4110);
PAINT MONO (-5515 4110);
DISPLAY INVISIBLE (-5515 4110);
FORCEPROP 1 LASTPIN (-5525 4100) BN 52
J 0
(-5577 4108);
DISPLAY 0.617021 (-5577 4108);
PAINT GREEN (-5577 4108);
FORCEPROP 2 LAST CDS_LIB mstr_standard
J 0
(-5575 4100);
PAINT MONO (-5575 4100);
DISPLAY INVISIBLE (-5575 4100);
FORCEPROP 1 LAST BODY_TYPE PLUMBING
J 0
(-5575 4050);
DISPLAY 1.595745 (-5575 4050);
PAINT GREEN (-5575 4050);
DISPLAY INVISIBLE (-5575 4050);
FORCEPROP 1 LAST HDL_TAP TRUE
J 0
(-5250 3975);
DISPLAY 1.595745 (-5250 3975);
PAINT GREEN (-5250 3975);
DISPLAY INVISIBLE (-5250 3975);
FORCEPROP 1 LAST PATH I75
J 0
(-5577 4100);
DISPLAY 0.872340 (-5577 4100);
PAINT GREEN (-5577 4100);
DISPLAY INVISIBLE (-5577 4100);
FORCEADD TAP..6
(-5575 4150);
FORCEPROP 3 LASTPIN (-5525 4150) SIG_NAME M_J_DQ<53>
J 0
(-5515 4160);
DISPLAY 0.659574 (-5515 4160);
PAINT MONO (-5515 4160);
DISPLAY INVISIBLE (-5515 4160);
FORCEPROP 1 LASTPIN (-5525 4150) BN 53
J 0
(-5577 4158);
DISPLAY 0.617021 (-5577 4158);
PAINT GREEN (-5577 4158);
FORCEPROP 2 LAST CDS_LIB mstr_standard
J 0
(-5575 4150);
PAINT MONO (-5575 4150);
DISPLAY INVISIBLE (-5575 4150);
FORCEPROP 1 LAST BODY_TYPE PLUMBING
J 0
(-5575 4100);
DISPLAY 1.595745 (-5575 4100);
PAINT GREEN (-5575 4100);
DISPLAY INVISIBLE (-5575 4100);
FORCEPROP 1 LAST HDL_TAP TRUE
J 0
(-5250 4025);
DISPLAY 1.595745 (-5250 4025);
PAINT GREEN (-5250 4025);
DISPLAY INVISIBLE (-5250 4025);
FORCEPROP 1 LAST PATH I76
J 0
(-5577 4150);
DISPLAY 0.872340 (-5577 4150);
PAINT GREEN (-5577 4150);
DISPLAY INVISIBLE (-5577 4150);
FORCEADD TAP..6
(-5575 4200);
FORCEPROP 3 LASTPIN (-5525 4200) SIG_NAME M_J_DQ<54>
J 0
(-5515 4210);
DISPLAY 0.659574 (-5515 4210);
PAINT MONO (-5515 4210);
DISPLAY INVISIBLE (-5515 4210);
FORCEPROP 1 LASTPIN (-5525 4200) BN 54
J 0
(-5577 4208);
DISPLAY 0.617021 (-5577 4208);
PAINT GREEN (-5577 4208);
FORCEPROP 2 LAST CDS_LIB mstr_standard
J 0
(-5575 4200);
PAINT MONO (-5575 4200);
DISPLAY INVISIBLE (-5575 4200);
FORCEPROP 1 LAST BODY_TYPE PLUMBING
J 0
(-5575 4150);
DISPLAY 1.595745 (-5575 4150);
PAINT GREEN (-5575 4150);
DISPLAY INVISIBLE (-5575 4150);
FORCEPROP 1 LAST HDL_TAP TRUE
J 0
(-5250 4075);
DISPLAY 1.595745 (-5250 4075);
PAINT GREEN (-5250 4075);
DISPLAY INVISIBLE (-5250 4075);
FORCEPROP 1 LAST PATH I77
J 0
(-5577 4200);
DISPLAY 0.872340 (-5577 4200);
PAINT GREEN (-5577 4200);
DISPLAY INVISIBLE (-5577 4200);
FORCEADD TAP..6
(-5575 4250);
FORCEPROP 3 LASTPIN (-5525 4250) SIG_NAME M_J_DQ<55>
J 0
(-5515 4260);
DISPLAY 0.659574 (-5515 4260);
PAINT MONO (-5515 4260);
DISPLAY INVISIBLE (-5515 4260);
FORCEPROP 1 LASTPIN (-5525 4250) BN 55
J 0
(-5577 4258);
DISPLAY 0.617021 (-5577 4258);
PAINT GREEN (-5577 4258);
FORCEPROP 2 LAST CDS_LIB mstr_standard
J 0
(-5575 4250);
PAINT MONO (-5575 4250);
DISPLAY INVISIBLE (-5575 4250);
FORCEPROP 1 LAST BODY_TYPE PLUMBING
J 0
(-5575 4200);
DISPLAY 1.595745 (-5575 4200);
PAINT GREEN (-5575 4200);
DISPLAY INVISIBLE (-5575 4200);
FORCEPROP 1 LAST HDL_TAP TRUE
J 0
(-5250 4125);
DISPLAY 1.595745 (-5250 4125);
PAINT GREEN (-5250 4125);
DISPLAY INVISIBLE (-5250 4125);
FORCEPROP 1 LAST PATH I78
J 0
(-5577 4250);
DISPLAY 0.872340 (-5577 4250);
PAINT GREEN (-5577 4250);
DISPLAY INVISIBLE (-5577 4250);
FORCEADD TAP..6
(-5575 4300);
FORCEPROP 3 LASTPIN (-5525 4300) SIG_NAME M_J_DQ<56>
J 0
(-5515 4310);
DISPLAY 0.659574 (-5515 4310);
PAINT MONO (-5515 4310);
DISPLAY INVISIBLE (-5515 4310);
FORCEPROP 1 LASTPIN (-5525 4300) BN 56
J 0
(-5577 4308);
DISPLAY 0.617021 (-5577 4308);
PAINT GREEN (-5577 4308);
FORCEPROP 2 LAST CDS_LIB mstr_standard
J 0
(-5575 4300);
PAINT MONO (-5575 4300);
DISPLAY INVISIBLE (-5575 4300);
FORCEPROP 1 LAST BODY_TYPE PLUMBING
J 0
(-5575 4250);
DISPLAY 1.595745 (-5575 4250);
PAINT GREEN (-5575 4250);
DISPLAY INVISIBLE (-5575 4250);
FORCEPROP 1 LAST HDL_TAP TRUE
J 0
(-5250 4175);
DISPLAY 1.595745 (-5250 4175);
PAINT GREEN (-5250 4175);
DISPLAY INVISIBLE (-5250 4175);
FORCEPROP 1 LAST PATH I79
J 0
(-5577 4300);
DISPLAY 0.872340 (-5577 4300);
PAINT GREEN (-5577 4300);
DISPLAY INVISIBLE (-5577 4300);
FORCEADD TAP..6
(-5575 700);
FORCEPROP 3 LASTPIN (-5525 700) SIG_NAME M_J_CLK_DN<2>
J 0
(-5515 710);
DISPLAY 0.659574 (-5515 710);
PAINT MONO (-5515 710);
DISPLAY INVISIBLE (-5515 710);
FORCEPROP 1 LASTPIN (-5525 700) BN 2
J 0
(-5577 708);
DISPLAY 0.617021 (-5577 708);
PAINT GREEN (-5577 708);
FORCEPROP 2 LAST CDS_LIB mstr_standard
J 0
(-5575 700);
PAINT MONO (-5575 700);
DISPLAY INVISIBLE (-5575 700);
FORCEPROP 1 LAST BODY_TYPE PLUMBING
J 0
(-5575 650);
DISPLAY 1.595745 (-5575 650);
PAINT GREEN (-5575 650);
DISPLAY INVISIBLE (-5575 650);
FORCEPROP 1 LAST HDL_TAP TRUE
J 0
(-5250 575);
DISPLAY 1.595745 (-5250 575);
PAINT GREEN (-5250 575);
DISPLAY INVISIBLE (-5250 575);
FORCEPROP 1 LAST PATH I8
J 0
(-5577 700);
DISPLAY 0.872340 (-5577 700);
PAINT GREEN (-5577 700);
DISPLAY INVISIBLE (-5577 700);
FORCEADD TAP..6
(-5575 4350);
FORCEPROP 3 LASTPIN (-5525 4350) SIG_NAME M_J_DQ<57>
J 0
(-5515 4360);
DISPLAY 0.659574 (-5515 4360);
PAINT MONO (-5515 4360);
DISPLAY INVISIBLE (-5515 4360);
FORCEPROP 1 LASTPIN (-5525 4350) BN 57
J 0
(-5577 4358);
DISPLAY 0.617021 (-5577 4358);
PAINT GREEN (-5577 4358);
FORCEPROP 2 LAST CDS_LIB mstr_standard
J 0
(-5575 4350);
PAINT MONO (-5575 4350);
DISPLAY INVISIBLE (-5575 4350);
FORCEPROP 1 LAST BODY_TYPE PLUMBING
J 0
(-5575 4300);
DISPLAY 1.595745 (-5575 4300);
PAINT GREEN (-5575 4300);
DISPLAY INVISIBLE (-5575 4300);
FORCEPROP 1 LAST HDL_TAP TRUE
J 0
(-5250 4225);
DISPLAY 1.595745 (-5250 4225);
PAINT GREEN (-5250 4225);
DISPLAY INVISIBLE (-5250 4225);
FORCEPROP 1 LAST PATH I80
J 0
(-5577 4350);
DISPLAY 0.872340 (-5577 4350);
PAINT GREEN (-5577 4350);
DISPLAY INVISIBLE (-5577 4350);
FORCEADD TAP..6
(-5575 4400);
FORCEPROP 3 LASTPIN (-5525 4400) SIG_NAME M_J_DQ<58>
J 0
(-5515 4410);
DISPLAY 0.659574 (-5515 4410);
PAINT MONO (-5515 4410);
DISPLAY INVISIBLE (-5515 4410);
FORCEPROP 1 LASTPIN (-5525 4400) BN 58
J 0
(-5577 4408);
DISPLAY 0.617021 (-5577 4408);
PAINT GREEN (-5577 4408);
FORCEPROP 2 LAST CDS_LIB mstr_standard
J 0
(-5575 4400);
PAINT MONO (-5575 4400);
DISPLAY INVISIBLE (-5575 4400);
FORCEPROP 1 LAST BODY_TYPE PLUMBING
J 0
(-5575 4350);
DISPLAY 1.595745 (-5575 4350);
PAINT GREEN (-5575 4350);
DISPLAY INVISIBLE (-5575 4350);
FORCEPROP 1 LAST HDL_TAP TRUE
J 0
(-5250 4275);
DISPLAY 1.595745 (-5250 4275);
PAINT GREEN (-5250 4275);
DISPLAY INVISIBLE (-5250 4275);
FORCEPROP 1 LAST PATH I81
J 0
(-5577 4400);
DISPLAY 0.872340 (-5577 4400);
PAINT GREEN (-5577 4400);
DISPLAY INVISIBLE (-5577 4400);
FORCEADD TAP..6
(-5575 4450);
FORCEPROP 3 LASTPIN (-5525 4450) SIG_NAME M_J_DQ<59>
J 0
(-5515 4460);
DISPLAY 0.659574 (-5515 4460);
PAINT MONO (-5515 4460);
DISPLAY INVISIBLE (-5515 4460);
FORCEPROP 1 LASTPIN (-5525 4450) BN 59
J 0
(-5577 4458);
DISPLAY 0.617021 (-5577 4458);
PAINT GREEN (-5577 4458);
FORCEPROP 2 LAST CDS_LIB mstr_standard
J 0
(-5575 4450);
PAINT MONO (-5575 4450);
DISPLAY INVISIBLE (-5575 4450);
FORCEPROP 1 LAST BODY_TYPE PLUMBING
J 0
(-5575 4400);
DISPLAY 1.595745 (-5575 4400);
PAINT GREEN (-5575 4400);
DISPLAY INVISIBLE (-5575 4400);
FORCEPROP 1 LAST HDL_TAP TRUE
J 0
(-5250 4325);
DISPLAY 1.595745 (-5250 4325);
PAINT GREEN (-5250 4325);
DISPLAY INVISIBLE (-5250 4325);
FORCEPROP 1 LAST PATH I82
J 0
(-5577 4450);
DISPLAY 0.872340 (-5577 4450);
PAINT GREEN (-5577 4450);
DISPLAY INVISIBLE (-5577 4450);
FORCEADD TAP..6
(-5575 4500);
FORCEPROP 3 LASTPIN (-5525 4500) SIG_NAME M_J_DQ<60>
J 0
(-5515 4510);
DISPLAY 0.659574 (-5515 4510);
PAINT MONO (-5515 4510);
DISPLAY INVISIBLE (-5515 4510);
FORCEPROP 1 LASTPIN (-5525 4500) BN 60
J 0
(-5577 4508);
DISPLAY 0.617021 (-5577 4508);
PAINT GREEN (-5577 4508);
FORCEPROP 2 LAST CDS_LIB mstr_standard
J 0
(-5575 4500);
PAINT MONO (-5575 4500);
DISPLAY INVISIBLE (-5575 4500);
FORCEPROP 1 LAST BODY_TYPE PLUMBING
J 0
(-5575 4450);
DISPLAY 1.595745 (-5575 4450);
PAINT GREEN (-5575 4450);
DISPLAY INVISIBLE (-5575 4450);
FORCEPROP 1 LAST HDL_TAP TRUE
J 0
(-5250 4375);
DISPLAY 1.595745 (-5250 4375);
PAINT GREEN (-5250 4375);
DISPLAY INVISIBLE (-5250 4375);
FORCEPROP 1 LAST PATH I83
J 0
(-5577 4500);
DISPLAY 0.872340 (-5577 4500);
PAINT GREEN (-5577 4500);
DISPLAY INVISIBLE (-5577 4500);
FORCEADD TAP..6
(-5575 4550);
FORCEPROP 3 LASTPIN (-5525 4550) SIG_NAME M_J_DQ<61>
J 0
(-5515 4560);
DISPLAY 0.659574 (-5515 4560);
PAINT MONO (-5515 4560);
DISPLAY INVISIBLE (-5515 4560);
FORCEPROP 1 LASTPIN (-5525 4550) BN 61
J 0
(-5577 4558);
DISPLAY 0.617021 (-5577 4558);
PAINT GREEN (-5577 4558);
FORCEPROP 2 LAST CDS_LIB mstr_standard
J 0
(-5575 4550);
PAINT MONO (-5575 4550);
DISPLAY INVISIBLE (-5575 4550);
FORCEPROP 1 LAST BODY_TYPE PLUMBING
J 0
(-5575 4500);
DISPLAY 1.595745 (-5575 4500);
PAINT GREEN (-5575 4500);
DISPLAY INVISIBLE (-5575 4500);
FORCEPROP 1 LAST HDL_TAP TRUE
J 0
(-5250 4425);
DISPLAY 1.595745 (-5250 4425);
PAINT GREEN (-5250 4425);
DISPLAY INVISIBLE (-5250 4425);
FORCEPROP 1 LAST PATH I84
J 0
(-5577 4550);
DISPLAY 0.872340 (-5577 4550);
PAINT GREEN (-5577 4550);
DISPLAY INVISIBLE (-5577 4550);
FORCEADD TAP..6
(-5575 4600);
FORCEPROP 3 LASTPIN (-5525 4600) SIG_NAME M_J_DQ<62>
J 0
(-5515 4610);
DISPLAY 0.659574 (-5515 4610);
PAINT MONO (-5515 4610);
DISPLAY INVISIBLE (-5515 4610);
FORCEPROP 1 LASTPIN (-5525 4600) BN 62
J 0
(-5577 4608);
DISPLAY 0.617021 (-5577 4608);
PAINT GREEN (-5577 4608);
FORCEPROP 2 LAST CDS_LIB mstr_standard
J 0
(-5575 4600);
PAINT MONO (-5575 4600);
DISPLAY INVISIBLE (-5575 4600);
FORCEPROP 1 LAST BODY_TYPE PLUMBING
J 0
(-5575 4550);
DISPLAY 1.595745 (-5575 4550);
PAINT GREEN (-5575 4550);
DISPLAY INVISIBLE (-5575 4550);
FORCEPROP 1 LAST HDL_TAP TRUE
J 0
(-5250 4475);
DISPLAY 1.595745 (-5250 4475);
PAINT GREEN (-5250 4475);
DISPLAY INVISIBLE (-5250 4475);
FORCEPROP 1 LAST PATH I85
J 0
(-5577 4600);
DISPLAY 0.872340 (-5577 4600);
PAINT GREEN (-5577 4600);
DISPLAY INVISIBLE (-5577 4600);
FORCEADD TAP..6
(-5575 4650);
FORCEPROP 3 LASTPIN (-5525 4650) SIG_NAME M_J_DQ<63>
J 0
(-5515 4660);
DISPLAY 0.659574 (-5515 4660);
PAINT MONO (-5515 4660);
DISPLAY INVISIBLE (-5515 4660);
FORCEPROP 1 LASTPIN (-5525 4650) BN 63
J 0
(-5577 4658);
DISPLAY 0.617021 (-5577 4658);
PAINT GREEN (-5577 4658);
FORCEPROP 2 LAST CDS_LIB mstr_standard
J 0
(-5575 4650);
PAINT MONO (-5575 4650);
DISPLAY INVISIBLE (-5575 4650);
FORCEPROP 1 LAST BODY_TYPE PLUMBING
J 0
(-5575 4600);
DISPLAY 1.595745 (-5575 4600);
PAINT GREEN (-5575 4600);
DISPLAY INVISIBLE (-5575 4600);
FORCEPROP 1 LAST HDL_TAP TRUE
J 0
(-5250 4525);
DISPLAY 1.595745 (-5250 4525);
PAINT GREEN (-5250 4525);
DISPLAY INVISIBLE (-5250 4525);
FORCEPROP 1 LAST PATH I86
J 0
(-5577 4650);
DISPLAY 0.872340 (-5577 4650);
PAINT GREEN (-5577 4650);
DISPLAY INVISIBLE (-5577 4650);
FORCEADD TAP..6
R 2
(-2850 750);
FORCEPROP 3 LASTPIN (-2900 750) SIG_NAME M_J_BA<1>
J 0
(-2890 760);
DISPLAY 0.659574 (-2890 760);
PAINT MONO (-2890 760);
DISPLAY INVISIBLE (-2890 760);
FORCEPROP 1 LASTPIN (-2900 750) BN 1
J 2
(-2848 758);
DISPLAY 0.617021 (-2848 758);
PAINT GREEN (-2848 758);
FORCEPROP 2 LAST CDS_LIB mstr_standard
J 0
(-2850 750);
PAINT MONO (-2850 750);
DISPLAY INVISIBLE (-2850 750);
FORCEPROP 1 LAST BODY_TYPE PLUMBING
J 2
(-2850 700);
DISPLAY 1.595745 (-2850 700);
PAINT GREEN (-2850 700);
DISPLAY INVISIBLE (-2850 700);
FORCEPROP 1 LAST HDL_TAP TRUE
J 2
(-3175 625);
DISPLAY 1.595745 (-3175 625);
PAINT GREEN (-3175 625);
DISPLAY INVISIBLE (-3175 625);
FORCEPROP 1 LAST PATH I87
J 2
(-2848 750);
DISPLAY 0.872340 (-2848 750);
PAINT GREEN (-2848 750);
DISPLAY INVISIBLE (-2848 750);
FORCEADD TAP..6
R 2
(-2850 700);
FORCEPROP 3 LASTPIN (-2900 700) SIG_NAME M_J_BA<0>
J 0
(-2890 710);
DISPLAY 0.659574 (-2890 710);
PAINT MONO (-2890 710);
DISPLAY INVISIBLE (-2890 710);
FORCEPROP 1 LASTPIN (-2900 700) BN 0
J 2
(-2848 708);
DISPLAY 0.617021 (-2848 708);
PAINT GREEN (-2848 708);
FORCEPROP 2 LAST CDS_LIB mstr_standard
J 0
(-2850 700);
PAINT MONO (-2850 700);
DISPLAY INVISIBLE (-2850 700);
FORCEPROP 1 LAST BODY_TYPE PLUMBING
J 2
(-2850 650);
DISPLAY 1.595745 (-2850 650);
PAINT GREEN (-2850 650);
DISPLAY INVISIBLE (-2850 650);
FORCEPROP 1 LAST HDL_TAP TRUE
J 2
(-3175 575);
DISPLAY 1.595745 (-3175 575);
PAINT GREEN (-3175 575);
DISPLAY INVISIBLE (-3175 575);
FORCEPROP 1 LAST PATH I88
J 2
(-2848 700);
DISPLAY 0.872340 (-2848 700);
PAINT GREEN (-2848 700);
DISPLAY INVISIBLE (-2848 700);
FORCEADD TAP..6
R 2
(-2850 800);
FORCEPROP 3 LASTPIN (-2900 800) SIG_NAME M_J_BG<0>
J 0
(-2890 810);
DISPLAY 0.659574 (-2890 810);
PAINT MONO (-2890 810);
DISPLAY INVISIBLE (-2890 810);
FORCEPROP 1 LASTPIN (-2900 800) BN 0
J 2
(-2848 808);
DISPLAY 0.617021 (-2848 808);
PAINT GREEN (-2848 808);
FORCEPROP 2 LAST CDS_LIB mstr_standard
J 0
(-2850 800);
PAINT MONO (-2850 800);
DISPLAY INVISIBLE (-2850 800);
FORCEPROP 1 LAST BODY_TYPE PLUMBING
J 2
(-2850 750);
DISPLAY 1.595745 (-2850 750);
PAINT GREEN (-2850 750);
DISPLAY INVISIBLE (-2850 750);
FORCEPROP 1 LAST HDL_TAP TRUE
J 2
(-3175 675);
DISPLAY 1.595745 (-3175 675);
PAINT GREEN (-3175 675);
DISPLAY INVISIBLE (-3175 675);
FORCEPROP 1 LAST PATH I89
J 2
(-2848 800);
DISPLAY 0.872340 (-2848 800);
PAINT GREEN (-2848 800);
DISPLAY INVISIBLE (-2848 800);
FORCEADD TAP..6
(-5575 850);
FORCEPROP 3 LASTPIN (-5525 850) SIG_NAME M_J_CLK_DP<1>
J 0
(-5515 860);
DISPLAY 0.659574 (-5515 860);
PAINT MONO (-5515 860);
DISPLAY INVISIBLE (-5515 860);
FORCEPROP 1 LASTPIN (-5525 850) BN 1
J 0
(-5577 858);
DISPLAY 0.617021 (-5577 858);
PAINT GREEN (-5577 858);
FORCEPROP 2 LAST CDS_LIB mstr_standard
J 0
(-5575 850);
PAINT MONO (-5575 850);
DISPLAY INVISIBLE (-5575 850);
FORCEPROP 1 LAST BODY_TYPE PLUMBING
J 0
(-5575 800);
DISPLAY 1.595745 (-5575 800);
PAINT GREEN (-5575 800);
DISPLAY INVISIBLE (-5575 800);
FORCEPROP 1 LAST HDL_TAP TRUE
J 0
(-5250 725);
DISPLAY 1.595745 (-5250 725);
PAINT GREEN (-5250 725);
DISPLAY INVISIBLE (-5250 725);
FORCEPROP 1 LAST PATH I9
J 0
(-5577 850);
DISPLAY 0.872340 (-5577 850);
PAINT GREEN (-5577 850);
DISPLAY INVISIBLE (-5577 850);
FORCEADD TAP..6
R 2
(-2850 850);
FORCEPROP 3 LASTPIN (-2900 850) SIG_NAME M_J_BG<1>
J 0
(-2890 860);
DISPLAY 0.659574 (-2890 860);
PAINT MONO (-2890 860);
DISPLAY INVISIBLE (-2890 860);
FORCEPROP 1 LASTPIN (-2900 850) BN 1
J 2
(-2848 858);
DISPLAY 0.617021 (-2848 858);
PAINT GREEN (-2848 858);
FORCEPROP 2 LAST CDS_LIB mstr_standard
J 0
(-2850 850);
PAINT MONO (-2850 850);
DISPLAY INVISIBLE (-2850 850);
FORCEPROP 1 LAST BODY_TYPE PLUMBING
J 2
(-2850 800);
DISPLAY 1.595745 (-2850 800);
PAINT GREEN (-2850 800);
DISPLAY INVISIBLE (-2850 800);
FORCEPROP 1 LAST HDL_TAP TRUE
J 2
(-3175 725);
DISPLAY 1.595745 (-3175 725);
PAINT GREEN (-3175 725);
DISPLAY INVISIBLE (-3175 725);
FORCEPROP 1 LAST PATH I90
J 2
(-2848 850);
DISPLAY 0.872340 (-2848 850);
PAINT GREEN (-2848 850);
DISPLAY INVISIBLE (-2848 850);
FORCEADD TAP..6
R 2
(-2850 1050);
FORCEPROP 3 LASTPIN (-2900 1050) SIG_NAME M_J_CS_N<2>
J 0
(-2890 1060);
DISPLAY 0.659574 (-2890 1060);
PAINT MONO (-2890 1060);
DISPLAY INVISIBLE (-2890 1060);
FORCEPROP 1 LASTPIN (-2900 1050) BN 2
J 2
(-2848 1058);
DISPLAY 0.617021 (-2848 1058);
PAINT GREEN (-2848 1058);
FORCEPROP 2 LAST CDS_LIB mstr_standard
J 0
(-2850 1050);
PAINT MONO (-2850 1050);
DISPLAY INVISIBLE (-2850 1050);
FORCEPROP 1 LAST BODY_TYPE PLUMBING
J 2
(-2850 1000);
DISPLAY 1.595745 (-2850 1000);
PAINT GREEN (-2850 1000);
DISPLAY INVISIBLE (-2850 1000);
FORCEPROP 1 LAST HDL_TAP TRUE
J 2
(-3175 925);
DISPLAY 1.595745 (-3175 925);
PAINT GREEN (-3175 925);
DISPLAY INVISIBLE (-3175 925);
FORCEPROP 1 LAST PATH I91
J 2
(-2848 1050);
DISPLAY 0.872340 (-2848 1050);
PAINT GREEN (-2848 1050);
DISPLAY INVISIBLE (-2848 1050);
FORCEADD TAP..6
R 2
(-2850 1000);
FORCEPROP 3 LASTPIN (-2900 1000) SIG_NAME M_J_CS_N<1>
J 0
(-2890 1010);
DISPLAY 0.659574 (-2890 1010);
PAINT MONO (-2890 1010);
DISPLAY INVISIBLE (-2890 1010);
FORCEPROP 1 LASTPIN (-2900 1000) BN 1
J 2
(-2848 1008);
DISPLAY 0.617021 (-2848 1008);
PAINT GREEN (-2848 1008);
FORCEPROP 2 LAST CDS_LIB mstr_standard
J 0
(-2850 1000);
PAINT MONO (-2850 1000);
DISPLAY INVISIBLE (-2850 1000);
FORCEPROP 1 LAST BODY_TYPE PLUMBING
J 2
(-2850 950);
DISPLAY 1.595745 (-2850 950);
PAINT GREEN (-2850 950);
DISPLAY INVISIBLE (-2850 950);
FORCEPROP 1 LAST HDL_TAP TRUE
J 2
(-3175 875);
DISPLAY 1.595745 (-3175 875);
PAINT GREEN (-3175 875);
DISPLAY INVISIBLE (-3175 875);
FORCEPROP 1 LAST PATH I92
J 2
(-2848 1000);
DISPLAY 0.872340 (-2848 1000);
PAINT GREEN (-2848 1000);
DISPLAY INVISIBLE (-2848 1000);
FORCEADD TAP..6
R 2
(-2850 950);
FORCEPROP 3 LASTPIN (-2900 950) SIG_NAME M_J_CS_N<0>
J 0
(-2890 960);
DISPLAY 0.659574 (-2890 960);
PAINT MONO (-2890 960);
DISPLAY INVISIBLE (-2890 960);
FORCEPROP 1 LASTPIN (-2900 950) BN 0
J 2
(-2848 958);
DISPLAY 0.617021 (-2848 958);
PAINT GREEN (-2848 958);
FORCEPROP 2 LAST CDS_LIB mstr_standard
J 0
(-2850 950);
PAINT MONO (-2850 950);
DISPLAY INVISIBLE (-2850 950);
FORCEPROP 1 LAST BODY_TYPE PLUMBING
J 2
(-2850 900);
DISPLAY 1.595745 (-2850 900);
PAINT GREEN (-2850 900);
DISPLAY INVISIBLE (-2850 900);
FORCEPROP 1 LAST HDL_TAP TRUE
J 2
(-3175 825);
DISPLAY 1.595745 (-3175 825);
PAINT GREEN (-3175 825);
DISPLAY INVISIBLE (-3175 825);
FORCEPROP 1 LAST PATH I93
J 2
(-2848 950);
DISPLAY 0.872340 (-2848 950);
PAINT GREEN (-2848 950);
DISPLAY INVISIBLE (-2848 950);
FORCEADD TAP..6
R 2
(-2850 1150);
FORCEPROP 3 LASTPIN (-2900 1150) SIG_NAME M_J_CS_N<4>
J 0
(-2890 1160);
DISPLAY 0.659574 (-2890 1160);
PAINT MONO (-2890 1160);
DISPLAY INVISIBLE (-2890 1160);
FORCEPROP 1 LASTPIN (-2900 1150) BN 4
J 2
(-2848 1158);
DISPLAY 0.617021 (-2848 1158);
PAINT GREEN (-2848 1158);
FORCEPROP 2 LAST CDS_LIB mstr_standard
J 0
(-2850 1150);
PAINT MONO (-2850 1150);
DISPLAY INVISIBLE (-2850 1150);
FORCEPROP 1 LAST BODY_TYPE PLUMBING
J 2
(-2850 1100);
DISPLAY 1.595745 (-2850 1100);
PAINT GREEN (-2850 1100);
DISPLAY INVISIBLE (-2850 1100);
FORCEPROP 1 LAST HDL_TAP TRUE
J 2
(-3175 1025);
DISPLAY 1.595745 (-3175 1025);
PAINT GREEN (-3175 1025);
DISPLAY INVISIBLE (-3175 1025);
FORCEPROP 1 LAST PATH I94
J 2
(-2848 1150);
DISPLAY 0.872340 (-2848 1150);
PAINT GREEN (-2848 1150);
DISPLAY INVISIBLE (-2848 1150);
FORCEADD TAP..6
R 2
(-2850 1100);
FORCEPROP 3 LASTPIN (-2900 1100) SIG_NAME M_J_CS_N<3>
J 0
(-2890 1110);
DISPLAY 0.659574 (-2890 1110);
PAINT MONO (-2890 1110);
DISPLAY INVISIBLE (-2890 1110);
FORCEPROP 1 LASTPIN (-2900 1100) BN 3
J 2
(-2848 1108);
DISPLAY 0.617021 (-2848 1108);
PAINT GREEN (-2848 1108);
FORCEPROP 2 LAST CDS_LIB mstr_standard
J 0
(-2850 1100);
PAINT MONO (-2850 1100);
DISPLAY INVISIBLE (-2850 1100);
FORCEPROP 1 LAST BODY_TYPE PLUMBING
J 2
(-2850 1050);
DISPLAY 1.595745 (-2850 1050);
PAINT GREEN (-2850 1050);
DISPLAY INVISIBLE (-2850 1050);
FORCEPROP 1 LAST HDL_TAP TRUE
J 2
(-3175 975);
DISPLAY 1.595745 (-3175 975);
PAINT GREEN (-3175 975);
DISPLAY INVISIBLE (-3175 975);
FORCEPROP 1 LAST PATH I95
J 2
(-2848 1100);
DISPLAY 0.872340 (-2848 1100);
PAINT GREEN (-2848 1100);
DISPLAY INVISIBLE (-2848 1100);
FORCEADD TAP..6
R 2
(-2850 1200);
FORCEPROP 3 LASTPIN (-2900 1200) SIG_NAME M_J_CS_N<5>
J 0
(-2890 1210);
DISPLAY 0.659574 (-2890 1210);
PAINT MONO (-2890 1210);
DISPLAY INVISIBLE (-2890 1210);
FORCEPROP 1 LASTPIN (-2900 1200) BN 5
J 2
(-2848 1208);
DISPLAY 0.617021 (-2848 1208);
PAINT GREEN (-2848 1208);
FORCEPROP 2 LAST CDS_LIB mstr_standard
J 0
(-2850 1200);
PAINT MONO (-2850 1200);
DISPLAY INVISIBLE (-2850 1200);
FORCEPROP 1 LAST BODY_TYPE PLUMBING
J 2
(-2850 1150);
DISPLAY 1.595745 (-2850 1150);
PAINT GREEN (-2850 1150);
DISPLAY INVISIBLE (-2850 1150);
FORCEPROP 1 LAST HDL_TAP TRUE
J 2
(-3175 1075);
DISPLAY 1.595745 (-3175 1075);
PAINT GREEN (-3175 1075);
DISPLAY INVISIBLE (-3175 1075);
FORCEPROP 1 LAST PATH I96
J 2
(-2848 1200);
DISPLAY 0.872340 (-2848 1200);
PAINT GREEN (-2848 1200);
DISPLAY INVISIBLE (-2848 1200);
FORCEADD TAP..6
R 2
(-2850 1250);
FORCEPROP 3 LASTPIN (-2900 1250) SIG_NAME M_J_CS_N<6>
J 0
(-2890 1260);
DISPLAY 0.659574 (-2890 1260);
PAINT MONO (-2890 1260);
DISPLAY INVISIBLE (-2890 1260);
FORCEPROP 1 LASTPIN (-2900 1250) BN 6
J 2
(-2848 1258);
DISPLAY 0.617021 (-2848 1258);
PAINT GREEN (-2848 1258);
FORCEPROP 2 LAST CDS_LIB mstr_standard
J 0
(-2850 1250);
PAINT MONO (-2850 1250);
DISPLAY INVISIBLE (-2850 1250);
FORCEPROP 1 LAST BODY_TYPE PLUMBING
J 2
(-2850 1200);
DISPLAY 1.595745 (-2850 1200);
PAINT GREEN (-2850 1200);
DISPLAY INVISIBLE (-2850 1200);
FORCEPROP 1 LAST HDL_TAP TRUE
J 2
(-3175 1125);
DISPLAY 1.595745 (-3175 1125);
PAINT GREEN (-3175 1125);
DISPLAY INVISIBLE (-3175 1125);
FORCEPROP 1 LAST PATH I97
J 2
(-2848 1250);
DISPLAY 0.872340 (-2848 1250);
PAINT GREEN (-2848 1250);
DISPLAY INVISIBLE (-2848 1250);
FORCEADD TAP..6
R 2
(-2850 1300);
FORCEPROP 3 LASTPIN (-2900 1300) SIG_NAME M_J_CS_N<7>
J 0
(-2890 1310);
DISPLAY 0.659574 (-2890 1310);
PAINT MONO (-2890 1310);
DISPLAY INVISIBLE (-2890 1310);
FORCEPROP 1 LASTPIN (-2900 1300) BN 7
J 2
(-2848 1308);
DISPLAY 0.617021 (-2848 1308);
PAINT GREEN (-2848 1308);
FORCEPROP 2 LAST CDS_LIB mstr_standard
J 0
(-2850 1300);
PAINT MONO (-2850 1300);
DISPLAY INVISIBLE (-2850 1300);
FORCEPROP 1 LAST BODY_TYPE PLUMBING
J 2
(-2850 1250);
DISPLAY 1.595745 (-2850 1250);
PAINT GREEN (-2850 1250);
DISPLAY INVISIBLE (-2850 1250);
FORCEPROP 1 LAST HDL_TAP TRUE
J 2
(-3175 1175);
DISPLAY 1.595745 (-3175 1175);
PAINT GREEN (-3175 1175);
DISPLAY INVISIBLE (-3175 1175);
FORCEPROP 1 LAST PATH I98
J 2
(-2848 1300);
DISPLAY 0.872340 (-2848 1300);
PAINT GREEN (-2848 1300);
DISPLAY INVISIBLE (-2848 1300);
FORCEADD TAP..6
R 2
(-2850 1400);
FORCEPROP 3 LASTPIN (-2900 1400) SIG_NAME M_J_ODT<0>
J 0
(-2890 1410);
DISPLAY 0.659574 (-2890 1410);
PAINT MONO (-2890 1410);
DISPLAY INVISIBLE (-2890 1410);
FORCEPROP 1 LASTPIN (-2900 1400) BN 0
J 2
(-2848 1408);
DISPLAY 0.617021 (-2848 1408);
PAINT GREEN (-2848 1408);
FORCEPROP 2 LAST CDS_LIB mstr_standard
J 0
(-2850 1400);
PAINT MONO (-2850 1400);
DISPLAY INVISIBLE (-2850 1400);
FORCEPROP 1 LAST BODY_TYPE PLUMBING
J 2
(-2850 1350);
DISPLAY 1.595745 (-2850 1350);
PAINT GREEN (-2850 1350);
DISPLAY INVISIBLE (-2850 1350);
FORCEPROP 1 LAST HDL_TAP TRUE
J 2
(-3175 1275);
DISPLAY 1.595745 (-3175 1275);
PAINT GREEN (-3175 1275);
DISPLAY INVISIBLE (-3175 1275);
FORCEPROP 1 LAST PATH I99
J 2
(-2848 1400);
DISPLAY 0.872340 (-2848 1400);
PAINT GREEN (-2848 1400);
DISPLAY INVISIBLE (-2848 1400);
FORCEADD DESIGN_NOTE..1
(-6325 375);
FORCEPROP 0 LAST L1 CPU SYMBOLS 1-30 ARE PRELIMINARY AND SUBJECT TO CHANGE
J 0
(-6525 250);
DISPLAY 1.021277 (-6525 250);
PAINT ORANGE (-6525 250);
FORCEPROP 2 LAST CDS_LIB mstr_symbols
J 0
(-6325 375);
PAINT ORANGE (-6325 375);
DISPLAY INVISIBLE (-6325 375);
FORCEPROP 1 LAST COMMENT_BODY TRUE
J 0
(-6300 475);
DISPLAY 0.978723 (-6300 475);
PAINT ORANGE (-6300 475);
DISPLAY INVISIBLE (-6300 475);
FORCEADD PRELIM..10
(-4215 2540);
PAINT GRAY (-4215 2540);
FORCEPROP 2 LAST CDS_LIB mstr_misc
J 0
(-4215 2540);
PAINT ORANGE (-4215 2540);
DISPLAY INVISIBLE (-4215 2540);
FORCEPROP 1 LAST COMMENT_BODY TRUE
J 0
(-4215 2540);
PAINT ORANGE (-4215 2540);
DISPLAY INVISIBLE (-4215 2540);
FORCEADD INTEL_CORP_BPAGE..1
(0 0);
FORCEPROP 1 LAST CDS_CON_LAST_MODIFIED Tue Dec 01 11:51:34 2015
J 0
(-1425 325);
DISPLAY 1.340426 (-1425 325);
PAINT GREEN (-1425 325);
DISPLAY INVISIBLE (-1425 325);
FORCEPROP 1 LAST CUSTOM_TXT_CDS <CURRENT_DESIGN_SHEET> OF <TOTAL_DESIGN_SHEETS>
J 0
(-500 25);
PAINT GREEN (-500 25);
FORCEPROP 1 LAST CUSTOM_TXT_CDS <CON_LAST_MODIFIED>
J 0
(-1925 350);
PAINT GREEN (-1925 350);
FORCEPROP 2 LAST CUSTOM_TXT_CDS <XR_PAGE_TITLE>
J 0
(-7890 5250);
DISPLAY 0.638298 (-7890 5250);
PAINT PINK (-7890 5250);
DISPLAY INVISIBLE (-7890 5250);
FORCEPROP 1 LAST SCH_ADDRESS3 Santa Clara, CA 95052-8119
J 0
(-3975 25);
DISPLAY 0.617021 (-3975 25);
PAINT GREEN (-3975 25);
FORCEPROP 1 LAST SCH_ADDRESS2 P.O. BOX 58119
J 0
(-3975 75);
DISPLAY 0.617021 (-3975 75);
PAINT GREEN (-3975 75);
FORCEPROP 1 LAST SCH_ADDRESS1 2200 Mission College Blvd.
J 0
(-3975 125);
DISPLAY 0.617021 (-3975 125);
PAINT GREEN (-3975 125);
FORCEPROP 1 LAST SCH_TITLE SKYLAKE - SKT1 - 5 OF 21
J 0
(-7950 50);
DISPLAY 1.212766 (-7950 50);
PAINT GREEN (-7950 50);
FORCEPROP 1 LAST SCH_NUMBER H4694802
J 0
(-1300 150);
DISPLAY 1.212766 (-1300 150);
PAINT YELLOW (-1300 150);
FORCEPROP 1 LAST SCH_DEPT BESD
J 1
(-4450 100);
DISPLAY 1.212766 (-4450 100);
PAINT YELLOW (-4450 100);
FORCEPROP 1 LAST SCH_REV 2.420
J 0
(-250 150);
DISPLAY 0.978723 (-250 150);
PAINT YELLOW (-250 150);
FORCEPROP 2 LAST CDS_LIB mstr_symbols
J 0
(0 0);
PAINT ORANGE (0 0);
DISPLAY INVISIBLE (0 0);
FORCEPROP 2 LAST PAGE_BORDER TRUE
J 0
(-7890 5250);
DISPLAY 0.851064 (-7890 5250);
PAINT PINK (-7890 5250);
DISPLAY INVISIBLE (-7890 5250);
FORCEPROP 1 LAST COMMENT_BODY TRUE
J 0
(12 12);
DISPLAY 0.638298 (12 12);
PAINT GREEN (12 12);
DISPLAY INVISIBLE (12 12);
FORCEPROP 2 LAST CDS_XR_PAGE_TITLE CR-59 : @BASEBOARD_FAB2_LIB.BASEBOARD_FAB2(SCH_1):PAGE59
J 0
(-7890 5250);
DISPLAY 0.638298 (-7890 5250);
PAINT PINK (-7890 5250);
DISPLAY INVISIBLE (-7890 5250);
WIRE 17 -1 (-2800 4675)(-2800 4725);
WIRE 17 -1 (-2800 4625)(-2800 4675);
WIRE 17 -1 (-2050 4725)(-2800 4725);
FORCEPROP 2 LAST SIG_NAME M_J_DQS_DP<17:0>
J 0
(-2700 4735);
DISPLAY 0.617021 (-2700 4735);
PAINT ORANGE (-2700 4735);
WIRE 17 -1 (-2800 4575)(-2800 4625);
WIRE 17 -1 (-2800 4525)(-2800 4575);
WIRE 17 -1 (-2800 4475)(-2800 4525);
WIRE 17 -1 (-2800 4425)(-2800 4475);
WIRE 17 -1 (-2800 4375)(-2800 4425);
WIRE 17 -1 (-2800 4325)(-2800 4375);
WIRE 17 -1 (-2800 4275)(-2800 4325);
WIRE 17 -1 (-2800 4225)(-2800 4275);
WIRE 17 -1 (-2800 4175)(-2800 4225);
WIRE 17 -1 (-2800 4125)(-2800 4175);
WIRE 17 -1 (-2800 4075)(-2800 4125);
WIRE 17 -1 (-2800 4025)(-2800 4075);
WIRE 17 -1 (-2800 3975)(-2800 4025);
WIRE 17 -1 (-2800 3925)(-2800 3975);
WIRE 17 -1 (-2800 3875)(-2800 3925);
WIRE 17 -1 (-2800 3825)(-2800 3875);
WIRE 17 -1 (-2800 3725)(-2800 3750);
WIRE 17 -1 (-2800 3675)(-2800 3725);
WIRE 17 -1 (-2050 3750)(-2800 3750);
FORCEPROP 2 LAST SIG_NAME M_J_DQS_DN<17:0>
J 0
(-2700 3760);
DISPLAY 0.617021 (-2700 3760);
PAINT ORANGE (-2700 3760);
WIRE 17 -1 (-2800 3625)(-2800 3675);
WIRE 17 -1 (-2800 3575)(-2800 3625);
WIRE 17 -1 (-2800 3525)(-2800 3575);
WIRE 17 -1 (-2800 3475)(-2800 3525);
WIRE 17 -1 (-2800 3425)(-2800 3475);
WIRE 17 -1 (-2800 3375)(-2800 3425);
WIRE 17 -1 (-2800 3325)(-2800 3375);
WIRE 17 -1 (-2800 3275)(-2800 3325);
WIRE 17 -1 (-2800 3225)(-2800 3275);
WIRE 17 -1 (-2800 3175)(-2800 3225);
WIRE 17 -1 (-2800 3125)(-2800 3175);
WIRE 17 -1 (-2800 3075)(-2800 3125);
WIRE 17 -1 (-2800 3025)(-2800 3075);
WIRE 17 -1 (-2800 2975)(-2800 3025);
WIRE 17 -1 (-2800 2925)(-2800 2975);
WIRE 17 -1 (-2800 2875)(-2800 2925);
WIRE 17 -1 (-2800 2775)(-2800 2800);
WIRE 17 -1 (-2800 2725)(-2800 2775);
WIRE 17 -1 (-2050 2800)(-2800 2800);
FORCEPROP 2 LAST SIG_NAME M_J_MA<17:0>
J 0
(-2700 2810);
DISPLAY 0.617021 (-2700 2810);
PAINT ORANGE (-2700 2810);
WIRE 17 -1 (-2800 2675)(-2800 2725);
WIRE 17 -1 (-2800 2625)(-2800 2675);
WIRE 17 -1 (-2800 2575)(-2800 2625);
WIRE 17 -1 (-2800 2525)(-2800 2575);
WIRE 17 -1 (-2800 2475)(-2800 2525);
WIRE 17 -1 (-2800 2425)(-2800 2475);
WIRE 17 -1 (-2800 2375)(-2800 2425);
WIRE 17 -1 (-2800 2325)(-2800 2375);
WIRE 17 -1 (-2800 2275)(-2800 2325);
WIRE 17 -1 (-2800 2225)(-2800 2275);
WIRE 17 -1 (-2800 2175)(-2800 2225);
WIRE 17 -1 (-2800 2125)(-2800 2175);
WIRE 17 -1 (-2800 2075)(-2800 2125);
WIRE 17 -1 (-2800 2025)(-2800 2075);
WIRE 17 -1 (-2800 1975)(-2800 2025);
WIRE 17 -1 (-2800 1925)(-2800 1975);
WIRE 17 -1 (-2800 775)(-2800 800);
WIRE 17 -1 (-2800 725)(-2800 775);
WIRE 17 -1 (-2050 800)(-2800 800);
FORCEPROP 2 LAST SIG_NAME M_J_BA<1:0>
J 0
(-2700 810);
DISPLAY 0.617021 (-2700 810);
PAINT ORANGE (-2700 810);
WIRE 17 -1 (-2800 825)(-2800 875);
WIRE 17 -1 (-2800 875)(-2800 900);
WIRE 17 -1 (-2050 900)(-2800 900);
FORCEPROP 2 LAST SIG_NAME M_J_BG<1:0>
J 0
(-2700 910);
DISPLAY 0.617021 (-2700 910);
PAINT ORANGE (-2700 910);
WIRE 17 -1 (-2800 1825)(-2800 1850);
WIRE 17 -1 (-2800 1775)(-2800 1825);
WIRE 17 -1 (-2050 1850)(-2800 1850);
FORCEPROP 2 LAST SIG_NAME M_J_CKE <3:0>
J 0
(-2700 1860);
DISPLAY 0.617021 (-2700 1860);
PAINT ORANGE (-2700 1860);
WIRE 17 -1 (-2800 1725)(-2800 1775);
WIRE 17 -1 (-2800 1675)(-2800 1725);
WIRE 17 -1 (-2800 1325)(-2800 1350);
WIRE 17 -1 (-2800 1275)(-2800 1325);
WIRE 17 -1 (-2050 1350)(-2800 1350);
FORCEPROP 2 LAST SIG_NAME M_J_CS_N<7:0>
J 0
(-2700 1360);
DISPLAY 0.617021 (-2700 1360);
PAINT ORANGE (-2700 1360);
WIRE 17 -1 (-2800 1225)(-2800 1275);
WIRE 17 -1 (-2800 1175)(-2800 1225);
WIRE 17 -1 (-2800 1125)(-2800 1175);
WIRE 17 -1 (-2800 1075)(-2800 1125);
WIRE 17 -1 (-2800 1025)(-2800 1075);
WIRE 17 -1 (-2800 975)(-2800 1025);
WIRE 17 -1 (-2800 1575)(-2800 1600);
WIRE 17 -1 (-2800 1525)(-2800 1575);
WIRE 17 -1 (-2050 1600)(-2800 1600);
FORCEPROP 2 LAST SIG_NAME M_J_ODT<3:0>
J 0
(-2700 1610);
DISPLAY 0.617021 (-2700 1610);
PAINT ORANGE (-2700 1610);
WIRE 17 -1 (-2800 1475)(-2800 1525);
WIRE 17 -1 (-2800 1425)(-2800 1475);
WIRE 17 -1 (-5625 4675)(-5625 4775);
WIRE 17 -1 (-5625 4625)(-5625 4675);
WIRE 17 -1 (-5625 4775)(-6375 4775);
FORCEPROP 2 LAST SIG_NAME M_J_DQ<63:0>
J 0
(-6325 4785);
DISPLAY 0.617021 (-6325 4785);
PAINT ORANGE (-6325 4785);
WIRE 17 -1 (-5625 4575)(-5625 4625);
WIRE 17 -1 (-5625 4525)(-5625 4575);
WIRE 17 -1 (-5625 4475)(-5625 4525);
WIRE 17 -1 (-5625 4425)(-5625 4475);
WIRE 17 -1 (-5625 4375)(-5625 4425);
WIRE 17 -1 (-5625 4325)(-5625 4375);
WIRE 17 -1 (-5625 4275)(-5625 4325);
WIRE 17 -1 (-5625 4225)(-5625 4275);
WIRE 17 -1 (-5625 4175)(-5625 4225);
WIRE 17 -1 (-5625 4125)(-5625 4175);
WIRE 17 -1 (-5625 4075)(-5625 4125);
WIRE 17 -1 (-5625 4025)(-5625 4075);
WIRE 17 -1 (-5625 3975)(-5625 4025);
WIRE 17 -1 (-5625 3925)(-5625 3975);
WIRE 17 -1 (-5625 3875)(-5625 3925);
WIRE 17 -1 (-5625 3825)(-5625 3875);
WIRE 17 -1 (-5625 3775)(-5625 3825);
WIRE 17 -1 (-5625 3725)(-5625 3775);
WIRE 17 -1 (-5625 3675)(-5625 3725);
WIRE 17 -1 (-5625 3625)(-5625 3675);
WIRE 17 -1 (-5625 3575)(-5625 3625);
WIRE 17 -1 (-5625 3525)(-5625 3575);
WIRE 17 -1 (-5625 3475)(-5625 3525);
WIRE 17 -1 (-5625 3425)(-5625 3475);
WIRE 17 -1 (-5625 3375)(-5625 3425);
WIRE 17 -1 (-5625 3325)(-5625 3375);
WIRE 17 -1 (-5625 3275)(-5625 3325);
WIRE 17 -1 (-5625 3225)(-5625 3275);
WIRE 17 -1 (-5625 3175)(-5625 3225);
WIRE 17 -1 (-5625 3125)(-5625 3175);
WIRE 17 -1 (-5625 3075)(-5625 3125);
WIRE 17 -1 (-5625 3025)(-5625 3075);
WIRE 17 -1 (-5625 2975)(-5625 3025);
WIRE 17 -1 (-5625 2925)(-5625 2975);
WIRE 17 -1 (-5625 2875)(-5625 2925);
WIRE 17 -1 (-5625 2825)(-5625 2875);
WIRE 17 -1 (-5625 2775)(-5625 2825);
WIRE 17 -1 (-5625 2725)(-5625 2775);
WIRE 17 -1 (-5625 2675)(-5625 2725);
WIRE 17 -1 (-5625 2625)(-5625 2675);
WIRE 17 -1 (-5625 2575)(-5625 2625);
WIRE 17 -1 (-5625 2525)(-5625 2575);
WIRE 17 -1 (-5625 2475)(-5625 2525);
WIRE 17 -1 (-5625 2425)(-5625 2475);
WIRE 17 -1 (-5625 2375)(-5625 2425);
WIRE 17 -1 (-5625 2325)(-5625 2375);
WIRE 17 -1 (-5625 2275)(-5625 2325);
WIRE 17 -1 (-5625 2225)(-5625 2275);
WIRE 17 -1 (-5625 2175)(-5625 2225);
WIRE 17 -1 (-5625 2125)(-5625 2175);
WIRE 17 -1 (-5625 2075)(-5625 2125);
WIRE 17 -1 (-5625 2025)(-5625 2075);
WIRE 17 -1 (-5625 1975)(-5625 2025);
WIRE 17 -1 (-5625 1925)(-5625 1975);
WIRE 17 -1 (-5625 1875)(-5625 1925);
WIRE 17 -1 (-5625 1825)(-5625 1875);
WIRE 17 -1 (-5625 1775)(-5625 1825);
WIRE 17 -1 (-5625 1725)(-5625 1775);
WIRE 17 -1 (-5625 1675)(-5625 1725);
WIRE 17 -1 (-5625 1625)(-5625 1675);
WIRE 17 -1 (-5625 1575)(-5625 1625);
WIRE 17 -1 (-5625 1525)(-5625 1575);
WIRE 17 -1 (-5625 775)(-5625 800);
WIRE 17 -1 (-5625 725)(-5625 775);
WIRE 17 -1 (-5625 800)(-6375 800);
FORCEPROP 2 LAST SIG_NAME M_J_CLK_DN<3:0>
J 0
(-6325 810);
DISPLAY 0.617021 (-6325 810);
PAINT ORANGE (-6325 810);
WIRE 17 -1 (-5625 675)(-5625 725);
WIRE 17 -1 (-5625 625)(-5625 675);
WIRE 17 -1 (-5625 975)(-5625 1000);
WIRE 17 -1 (-5625 925)(-5625 975);
WIRE 17 -1 (-5625 1000)(-6375 1000);
FORCEPROP 2 LAST SIG_NAME M_J_CLK_DP<3:0>
J 0
(-6325 1010);
DISPLAY 0.617021 (-6325 1010);
PAINT ORANGE (-6325 1010);
WIRE 17 -1 (-5625 875)(-5625 925);
WIRE 17 -1 (-5625 825)(-5625 875);
WIRE 17 -1 (-5625 1425)(-5625 1450);
WIRE 17 -1 (-5625 1375)(-5625 1425);
WIRE 17 -1 (-5625 1450)(-6375 1450);
FORCEPROP 2 LAST SIG_NAME M_J_ECC<7:0>
J 0
(-6325 1460);
DISPLAY 0.617021 (-6325 1460);
PAINT ORANGE (-6325 1460);
WIRE 17 -1 (-5625 1325)(-5625 1375);
WIRE 17 -1 (-5625 1275)(-5625 1325);
WIRE 17 -1 (-5625 1225)(-5625 1275);
WIRE 17 -1 (-5625 1175)(-5625 1225);
WIRE 17 -1 (-5625 1125)(-5625 1175);
WIRE 17 -1 (-5625 1075)(-5625 1125);
WIRE 16 -1 (-5025 500)(-6375 500);
FORCEPROP 2 LAST SIG_NAME M_J_C<2>
J 0
(-6325 510);
DISPLAY 0.617021 (-6325 510);
PAINT ORANGE (-6325 510);
WIRE 16 -1 (-5025 1050)(-5525 1050);
WIRE 16 -1 (-5025 1100)(-5525 1100);
WIRE 16 -1 (-5025 1150)(-5525 1150);
WIRE 16 -1 (-5025 1200)(-5525 1200);
WIRE 16 -1 (-5025 1250)(-5525 1250);
WIRE 16 -1 (-5025 1300)(-5525 1300);
WIRE 16 -1 (-5025 1350)(-5525 1350);
WIRE 16 -1 (-5025 1400)(-5525 1400);
WIRE 16 -1 (-5525 1500)(-5025 1500);
WIRE 16 -1 (-5525 1550)(-5025 1550);
WIRE 16 -1 (-5525 1600)(-5025 1600);
WIRE 16 -1 (-5025 1650)(-5525 1650);
WIRE 16 -1 (-5525 1700)(-5025 1700);
WIRE 16 -1 (-5525 1750)(-5025 1750);
WIRE 16 -1 (-5025 1800)(-5525 1800);
WIRE 16 -1 (-5525 1850)(-5025 1850);
WIRE 16 -1 (-5525 1900)(-5025 1900);
WIRE 16 -1 (-5525 1950)(-5025 1950);
WIRE 16 -1 (-5525 2000)(-5025 2000);
WIRE 16 -1 (-5025 800)(-5525 800);
WIRE 16 -1 (-5025 850)(-5525 850);
WIRE 16 -1 (-5025 900)(-5525 900);
WIRE 16 -1 (-5025 950)(-5525 950);
WIRE 16 -1 (-5025 600)(-5525 600);
WIRE 16 -1 (-5025 650)(-5525 650);
WIRE 16 -1 (-5025 700)(-5525 700);
WIRE 16 -1 (-5025 750)(-5525 750);
WIRE 16 -1 (-5525 2050)(-5025 2050);
WIRE 16 -1 (-5525 2100)(-5025 2100);
WIRE 16 -1 (-5525 2150)(-5025 2150);
WIRE 16 -1 (-5525 2200)(-5025 2200);
WIRE 16 -1 (-5025 2250)(-5525 2250);
WIRE 16 -1 (-5525 2300)(-5025 2300);
WIRE 16 -1 (-5525 2350)(-5025 2350);
WIRE 16 -1 (-5025 2400)(-5525 2400);
WIRE 16 -1 (-5525 2450)(-5025 2450);
WIRE 16 -1 (-5525 2500)(-5025 2500);
WIRE 16 -1 (-5525 2550)(-5025 2550);
WIRE 16 -1 (-5525 2600)(-5025 2600);
WIRE 16 -1 (-5025 2650)(-5525 2650);
WIRE 16 -1 (-5525 2700)(-5025 2700);
WIRE 16 -1 (-5525 2750)(-5025 2750);
WIRE 16 -1 (-5525 2800)(-5025 2800);
WIRE 16 -1 (-5525 2850)(-5025 2850);
WIRE 16 -1 (-5525 2900)(-5025 2900);
WIRE 16 -1 (-5525 2950)(-5025 2950);
WIRE 16 -1 (-5025 3000)(-5525 3000);
WIRE 16 -1 (-5525 3050)(-5025 3050);
WIRE 16 -1 (-5525 3100)(-5025 3100);
WIRE 16 -1 (-5525 3150)(-5025 3150);
WIRE 16 -1 (-5525 3200)(-5025 3200);
WIRE 16 -1 (-5525 3250)(-5025 3250);
WIRE 16 -1 (-5525 3300)(-5025 3300);
WIRE 16 -1 (-5025 3350)(-5525 3350);
WIRE 16 -1 (-5525 3400)(-5025 3400);
WIRE 16 -1 (-5525 3450)(-5025 3450);
WIRE 16 -1 (-5025 3500)(-5525 3500);
WIRE 16 -1 (-5525 3550)(-5025 3550);
WIRE 16 -1 (-5525 3600)(-5025 3600);
WIRE 16 -1 (-5025 3650)(-5525 3650);
WIRE 16 -1 (-5025 3700)(-5525 3700);
WIRE 16 -1 (-5025 3750)(-5525 3750);
WIRE 16 -1 (-5025 3800)(-5525 3800);
WIRE 16 -1 (-5025 3850)(-5525 3850);
WIRE 16 -1 (-5025 3900)(-5525 3900);
WIRE 16 -1 (-5025 3950)(-5525 3950);
WIRE 16 -1 (-5025 4000)(-5525 4000);
WIRE 16 -1 (-5025 4050)(-5525 4050);
WIRE 16 -1 (-5025 4100)(-5525 4100);
WIRE 16 -1 (-5025 4150)(-5525 4150);
WIRE 16 -1 (-5025 4200)(-5525 4200);
WIRE 16 -1 (-5025 4250)(-5525 4250);
WIRE 16 -1 (-5025 4300)(-5525 4300);
WIRE 16 -1 (-5025 4350)(-5525 4350);
WIRE 16 -1 (-5025 4400)(-5525 4400);
WIRE 16 -1 (-5025 4450)(-5525 4450);
WIRE 16 -1 (-5025 4500)(-5525 4500);
WIRE 16 -1 (-5025 4550)(-5525 4550);
WIRE 16 -1 (-5025 4600)(-5525 4600);
WIRE 16 -1 (-5025 4650)(-5525 4650);
WIRE 16 -1 (-3325 1400)(-2900 1400);
WIRE 16 -1 (-3325 1450)(-2900 1450);
WIRE 16 -1 (-3325 1500)(-2900 1500);
WIRE 16 -1 (-3325 1550)(-2900 1550);
WIRE 16 -1 (-3325 1900)(-2900 1900);
WIRE 16 -1 (-3325 1950)(-2900 1950);
WIRE 16 -1 (-3325 2000)(-2900 2000);
WIRE 16 -1 (-3325 950)(-2900 950);
WIRE 16 -1 (-3325 1000)(-2900 1000);
WIRE 16 -1 (-3325 1050)(-2900 1050);
WIRE 16 -1 (-3325 1100)(-2900 1100);
WIRE 16 -1 (-3325 1150)(-2900 1150);
WIRE 16 -1 (-3325 1200)(-2900 1200);
WIRE 16 -1 (-3325 1250)(-2900 1250);
WIRE 16 -1 (-3325 1300)(-2900 1300);
WIRE 16 -1 (-3325 1650)(-2900 1650);
WIRE 16 -1 (-3325 1700)(-2900 1700);
WIRE 16 -1 (-3325 1750)(-2900 1750);
WIRE 16 -1 (-3325 1800)(-2900 1800);
WIRE 16 -1 (-3325 800)(-2900 800);
WIRE 16 -1 (-3325 850)(-2900 850);
WIRE 16 -1 (-3325 700)(-2900 700);
WIRE 16 -1 (-3325 750)(-2900 750);
WIRE 16 -1 (-3325 2050)(-2900 2050);
WIRE 16 -1 (-3325 2100)(-2900 2100);
WIRE 16 -1 (-3325 2150)(-2900 2150);
WIRE 16 -1 (-3325 2200)(-2900 2200);
WIRE 16 -1 (-3325 2250)(-2900 2250);
WIRE 16 -1 (-3325 2300)(-2900 2300);
WIRE 16 -1 (-3325 2350)(-2900 2350);
WIRE 16 -1 (-3325 2400)(-2900 2400);
WIRE 16 -1 (-3325 2450)(-2900 2450);
WIRE 16 -1 (-3325 2500)(-2900 2500);
WIRE 16 -1 (-3325 2550)(-2900 2550);
WIRE 16 -1 (-3325 2600)(-2900 2600);
WIRE 16 -1 (-3325 2650)(-2900 2650);
WIRE 16 -1 (-3325 2700)(-2900 2700);
WIRE 16 -1 (-3325 2750)(-2900 2750);
WIRE 16 -1 (-3325 3800)(-2900 3800);
WIRE 16 -1 (-3325 3850)(-2900 3850);
WIRE 16 -1 (-3325 3900)(-2900 3900);
WIRE 16 -1 (-3325 3950)(-2900 3950);
WIRE 16 -1 (-3325 4000)(-2900 4000);
WIRE 16 -1 (-3325 4050)(-2900 4050);
WIRE 16 -1 (-3325 2850)(-2900 2850);
WIRE 16 -1 (-3325 2900)(-2900 2900);
WIRE 16 -1 (-3325 2950)(-2900 2950);
WIRE 16 -1 (-3325 3000)(-2900 3000);
WIRE 16 -1 (-3325 3050)(-2900 3050);
WIRE 16 -1 (-3325 3100)(-2900 3100);
WIRE 16 -1 (-3325 3150)(-2900 3150);
WIRE 16 -1 (-3325 3200)(-2900 3200);
WIRE 16 -1 (-3325 3250)(-2900 3250);
WIRE 16 -1 (-3325 3300)(-2900 3300);
WIRE 16 -1 (-3325 3350)(-2900 3350);
WIRE 16 -1 (-3325 3400)(-2900 3400);
WIRE 16 -1 (-3325 3450)(-2900 3450);
WIRE 16 -1 (-3325 3500)(-2900 3500);
WIRE 16 -1 (-3325 3550)(-2900 3550);
WIRE 16 -1 (-3325 3600)(-2900 3600);
WIRE 16 -1 (-3325 3650)(-2900 3650);
WIRE 16 -1 (-3325 3700)(-2900 3700);
WIRE 16 -1 (-3325 500)(-2025 500);
FORCEPROP 2 LAST SIG_NAME M_J_PAR
J 0
(-2700 510);
DISPLAY 0.617021 (-2700 510);
PAINT ORANGE (-2700 510);
WIRE 16 -1 (-3325 550)(-2025 550);
FORCEPROP 2 LAST SIG_NAME M_J_ALERT_N
J 0
(-2700 560);
DISPLAY 0.617021 (-2700 560);
PAINT ORANGE (-2700 560);
WIRE 16 -1 (-3325 600)(-2025 600);
FORCEPROP 2 LAST SIG_NAME M_J_ACT_N
J 0
(-2700 610);
DISPLAY 0.617021 (-2700 610);
PAINT ORANGE (-2700 610);
WIRE 16 -1 (-3325 4100)(-2900 4100);
WIRE 16 -1 (-3325 4150)(-2900 4150);
WIRE 16 -1 (-3325 4200)(-2900 4200);
WIRE 16 -1 (-3325 4250)(-2900 4250);
WIRE 16 -1 (-3325 4300)(-2900 4300);
WIRE 16 -1 (-3325 4350)(-2900 4350);
WIRE 16 -1 (-3325 4400)(-2900 4400);
WIRE 16 -1 (-3325 4450)(-2900 4450);
WIRE 16 -1 (-3325 4500)(-2900 4500);
WIRE 16 -1 (-3325 4550)(-2900 4550);
WIRE 16 -1 (-3325 4600)(-2900 4600);
WIRE 16 -1 (-3325 4650)(-2900 4650);
FORCENOTE
BOM_COST=PROC_SOCKET
(-7925 250) 0;
DISPLAY LEFT (-7925 250);
DISPLAY 1.723404 (-7925 250);
PAINT PURPLE (-7925 250);
FORCENOTE
ROOM=CPU1
(-7925 375) 0;
DISPLAY LEFT (-7925 375);
DISPLAY 1.723404 (-7925 375);
PAINT PURPLE (-7925 375);
QUIT
